FILE_TYPE = MACRO_DRAWING;
SET COLOR_WIRE YELLOW;
SET COLOR_PROP MONO;
SET COLOR_DOT WHITE;
SET COLOR_ARC YELLOW;
SET COLOR_BODY GREEN;
SET COLOR_NOTE MONO;
SET PROP_DISPLAY VALUE;
SET PAGE_NUMBER P235;
FORCEADD P3V3_STBY..1
(-8400 5300);
FORCEPROP 3 LASTPIN (-8400 5250) SIG_NAME P3V3_STBY\g
J 0
(-8390 5260);
DISPLAY 0.659574 (-8390 5260);
PAINT MONO (-8390 5260);
DISPLAY INVISIBLE (-8390 5260);
FORCEPROP 1 LAST SIZE 1B
J 0
(-8355 5322);
DISPLAY 0.340426 (-8355 5322);
PAINT GREEN (-8355 5322);
DISPLAY INVISIBLE (-8355 5322);
FORCEPROP 1 LAST PATH I135
J 0
(-8355 5302);
DISPLAY 0.340426 (-8355 5302);
PAINT GREEN (-8355 5302);
DISPLAY INVISIBLE (-8355 5302);
FORCEPROP 2 LAST CDS_LIB mstr_symbols
J 0
(-8400 5300);
PAINT ORANGE (-8400 5300);
DISPLAY INVISIBLE (-8400 5300);
FORCEPROP 1 LAST VOLTAGE 3.3V
J 0
(-8445 5257);
DISPLAY 0.340426 (-8445 5257);
PAINT SKYBLUE (-8445 5257);
DISPLAY INVISIBLE (-8445 5257);
FORCEPROP 1 LAST BODY_TYPE PLUMBING
J 0
(-8445 5257);
DISPLAY 0.340426 (-8445 5257);
PAINT GREEN (-8445 5257);
DISPLAY INVISIBLE (-8445 5257);
FORCEPROP 1 LAST HDL_POWER P3V3_STBY
J 0
(-8700 5175);
DISPLAY 0.872340 (-8700 5175);
PAINT ORANGE (-8700 5175);
DISPLAY INVISIBLE (-8700 5175);
FORCEADD OFFPAGE..2
(-6275 4500);
FORCEPROP 2 LAST $XR0 190 
J 0
(-6086 4500);
DISPLAY 0.638298 (-6086 4500);
PAINT MONO (-6086 4500);
FORCEPROP 1 LAST COMMENT_BODY TRUE
J 0
(-6320 4405);
DISPLAY 1.170213 (-6320 4405);
PAINT GREEN (-6320 4405);
DISPLAY INVISIBLE (-6320 4405);
FORCEPROP 1 LAST OFFPAGE TRUE
J 0
(-5950 4375);
DISPLAY 1.170213 (-5950 4375);
PAINT GREEN (-5950 4375);
DISPLAY INVISIBLE (-5950 4375);
FORCEPROP 2 LAST ROOM PVNN_PCH_STBY
J 0
(-6700 4575);
DISPLAY 1.361702 (-6700 4575);
PAINT ORANGE (-6700 4575);
DISPLAY INVISIBLE (-6700 4575);
FORCEPROP 2 LAST CDS_LIB mstr_standard
J 0
(-6275 4500);
PAINT ORANGE (-6275 4500);
DISPLAY INVISIBLE (-6275 4500);
FORCEPROP 2 LAST PATH I136
J 0
(-6100 4575);
DISPLAY 1.021277 (-6100 4575);
PAINT ORANGE (-6100 4575);
DISPLAY INVISIBLE (-6100 4575);
FORCEADD OFFPAGE..2
(-7125 3900);
FORCEPROP 2 LAST $XR0 236 
J 0
(-6936 3900);
DISPLAY 0.638298 (-6936 3900);
PAINT MONO (-6936 3900);
FORCEPROP 1 LAST COMMENT_BODY TRUE
J 0
(-7170 3805);
DISPLAY 1.170213 (-7170 3805);
PAINT GREEN (-7170 3805);
DISPLAY INVISIBLE (-7170 3805);
FORCEPROP 1 LAST OFFPAGE TRUE
J 0
(-6800 3775);
DISPLAY 1.170213 (-6800 3775);
PAINT GREEN (-6800 3775);
DISPLAY INVISIBLE (-6800 3775);
FORCEPROP 2 LAST ROOM PVNN_PCH_STBY
J 0
(-7550 3975);
DISPLAY 1.361702 (-7550 3975);
PAINT ORANGE (-7550 3975);
DISPLAY INVISIBLE (-7550 3975);
FORCEPROP 2 LAST CDS_LIB mstr_standard
J 0
(-7125 3900);
PAINT ORANGE (-7125 3900);
DISPLAY INVISIBLE (-7125 3900);
FORCEPROP 2 LAST PATH I139
J 0
(-6925 3950);
DISPLAY 1.021277 (-6925 3950);
PAINT ORANGE (-6925 3950);
DISPLAY INVISIBLE (-6925 3950);
FORCEADD OFFPAGE..1
R 2
(-8100 2150);
FORCEPROP 2 LAST $XR0 235 
J 0
(-7914 2150);
DISPLAY 0.638298 (-7914 2150);
PAINT MONO (-7914 2150);
FORCEPROP 1 LAST COMMENT_BODY TRUE
J 2
(-8225 2050);
DISPLAY 1.170213 (-8225 2050);
PAINT GREEN (-8225 2050);
DISPLAY INVISIBLE (-8225 2050);
FORCEPROP 1 LAST OFFPAGE TRUE
J 2
(-8425 2025);
DISPLAY 1.170213 (-8425 2025);
PAINT GREEN (-8425 2025);
DISPLAY INVISIBLE (-8425 2025);
FORCEPROP 2 LAST ROOM PVNN_PCH_STBY
J 0
(-8525 2225);
DISPLAY 1.361702 (-8525 2225);
PAINT ORANGE (-8525 2225);
DISPLAY INVISIBLE (-8525 2225);
FORCEPROP 2 LAST CDS_LIB mstr_standard
J 2
(-8100 2150);
PAINT ORANGE (-8100 2150);
DISPLAY INVISIBLE (-8100 2150);
FORCEPROP 2 LAST PATH I142
J 0
(-7775 2200);
DISPLAY 1.021277 (-7775 2200);
PAINT ORANGE (-7775 2200);
DISPLAY INVISIBLE (-7775 2200);
FORCEADD CAP_A..1
(-8800 1975);
FORCEPROP 1 LAST LOCATION C8A7
J 0
(-8750 2075);
DISPLAY 0.617021 (-8750 2075);
PAINT AQUA (-8750 2075);
FORCEPROP 1 LAST PART_NUMBER D97712-004
J 0
(-8750 1825);
DISPLAY 0.617021 (-8750 1825);
PAINT BLUE (-8750 1825);
FORCEPROP 1 LAST PACK_TYPE 0402V
J 0
(-8750 1775);
DISPLAY 0.617021 (-8750 1775);
PAINT SKYBLUE (-8750 1775);
FORCEPROP 1 LASTPIN (-8800 2075) $PN 1
J 0
(-8790 2055);
DISPLAY 0.617021 (-8790 2055);
PAINT ORANGE (-8790 2055);
FORCEPROP 1 LAST MATERIAL X6S
J 0
(-8750 1875);
DISPLAY 0.617021 (-8750 1875);
PAINT SKYBLUE (-8750 1875);
FORCEPROP 1 LAST VALUE 1.0UF
J 0
(-8750 2025);
DISPLAY 0.617021 (-8750 2025);
PAINT SKYBLUE (-8750 2025);
FORCEPROP 1 LASTPIN (-8800 1875) $PN 2
J 0
(-8790 1855);
DISPLAY 0.617021 (-8790 1855);
PAINT ORANGE (-8790 1855);
FORCEPROP 1 LAST TOLERANCE 10%
J 0
(-8750 1925);
DISPLAY 0.617021 (-8750 1925);
PAINT SKYBLUE (-8750 1925);
FORCEPROP 1 LAST VOLTAGE 6.3V
J 0
(-8750 1975);
DISPLAY 0.617021 (-8750 1975);
PAINT SKYBLUE (-8750 1975);
FORCEPROP 2 LAST CDS_LIB dev_discrete
J 0
(-8800 1975);
PAINT ORANGE (-8800 1975);
DISPLAY INVISIBLE (-8800 1975);
FORCEPROP 2 LAST CDS_LOCATION C8A7
J 0
(-8750 2075);
DISPLAY 0.617021 (-8750 2075);
PAINT AQUA (-8750 2075);
DISPLAY INVISIBLE (-8750 2075);
FORCEPROP 2 LAST CDS_SEC 1
J 0
(-8750 2125);
PAINT ORANGE (-8750 2125);
DISPLAY INVISIBLE (-8750 2125);
FORCEPROP 2 LAST SEC_TYPE 0402V
J 0
(-8750 2175);
DISPLAY 1.021277 (-8750 2175);
PAINT ORANGE (-8750 2175);
DISPLAY INVISIBLE (-8750 2175);
FORCEPROP 2 LAST SEC 1
J 0
(-8750 2175);
DISPLAY 0.680851 (-8750 2175);
PAINT MONO (-8750 2175);
DISPLAY INVISIBLE (-8750 2175);
FORCEPROP 1 LAST PATH I143
J 0
(-8750 2125);
DISPLAY 0.978723 (-8750 2125);
PAINT WHITE (-8750 2125);
DISPLAY INVISIBLE (-8750 2125);
FORCEPROP 2 LAST ROOM PVNN_PCH_STBY
J 0
(-8750 2125);
DISPLAY 1.361702 (-8750 2125);
PAINT ORANGE (-8750 2125);
DISPLAY INVISIBLE (-8750 2125);
FORCEADD GND..1
(-8800 1750);
FORCEPROP 3 LASTPIN (-8800 1800) SIG_NAME GND\g
J 0
(-8790 1810);
DISPLAY 0.659574 (-8790 1810);
PAINT MONO (-8790 1810);
DISPLAY INVISIBLE (-8790 1810);
FORCEPROP 1 LAST HDL_POWER GND
J 0
(-8800 1900);
DISPLAY 1.170213 (-8800 1900);
PAINT GREEN (-8800 1900);
DISPLAY INVISIBLE (-8800 1900);
FORCEPROP 1 LAST BODY_TYPE PLUMBING
J 0
(-8845 1707);
DISPLAY 0.340426 (-8845 1707);
PAINT GREEN (-8845 1707);
DISPLAY INVISIBLE (-8845 1707);
FORCEPROP 2 LAST ROOM PVNN_PCH_STBY
J 0
(-9375 1825);
DISPLAY 1.361702 (-9375 1825);
PAINT ORANGE (-9375 1825);
DISPLAY INVISIBLE (-9375 1825);
FORCEPROP 1 LAST SIZE 1B
J 0
(-8725 1700);
DISPLAY 1.170213 (-8725 1700);
PAINT AQUA (-8725 1700);
DISPLAY INVISIBLE (-8725 1700);
FORCEPROP 1 LAST PATH I144
J 0
(-8725 1750);
DISPLAY 0.872340 (-8725 1750);
PAINT AQUA (-8725 1750);
DISPLAY INVISIBLE (-8725 1750);
FORCEPROP 1 LAST VOLTAGE 0
J 0
(-8800 1750);
PAINT SKYBLUE (-8800 1750);
DISPLAY INVISIBLE (-8800 1750);
FORCEPROP 2 LAST CDS_LIB mstr_symbols
J 0
(-8800 1750);
PAINT ORANGE (-8800 1750);
DISPLAY INVISIBLE (-8800 1750);
FORCEADD CAP_A..1
(-9200 1975);
FORCEPROP 1 LAST VOLTAGE 16V
J 0
(-9150 1975);
DISPLAY 0.617021 (-9150 1975);
PAINT SKYBLUE (-9150 1975);
FORCEPROP 1 LAST TOLERANCE 10%
J 0
(-9150 1925);
DISPLAY 0.617021 (-9150 1925);
PAINT SKYBLUE (-9150 1925);
FORCEPROP 1 LAST PART_NUMBER A36096-030
J 0
(-9150 1825);
DISPLAY 0.617021 (-9150 1825);
PAINT BLUE (-9150 1825);
FORCEPROP 1 LAST VALUE 0.1UF
J 0
(-9150 2025);
DISPLAY 0.617021 (-9150 2025);
PAINT SKYBLUE (-9150 2025);
FORCEPROP 1 LAST LOCATION C8A8
J 0
(-9150 2075);
DISPLAY 0.617021 (-9150 2075);
PAINT AQUA (-9150 2075);
FORCEPROP 1 LASTPIN (-9200 2075) $PN 1
J 0
(-9190 2055);
DISPLAY 0.617021 (-9190 2055);
PAINT ORANGE (-9190 2055);
FORCEPROP 1 LAST PACK_TYPE 0402V
J 0
(-9150 1775);
DISPLAY 0.617021 (-9150 1775);
PAINT SKYBLUE (-9150 1775);
FORCEPROP 1 LAST MATERIAL X7R
J 0
(-9150 1875);
DISPLAY 0.617021 (-9150 1875);
PAINT SKYBLUE (-9150 1875);
FORCEPROP 1 LASTPIN (-9200 1875) $PN 2
J 0
(-9190 1855);
DISPLAY 0.617021 (-9190 1855);
PAINT ORANGE (-9190 1855);
FORCEPROP 2 LAST CDS_LIB dev_discrete
J 0
(-9200 1975);
PAINT ORANGE (-9200 1975);
DISPLAY INVISIBLE (-9200 1975);
FORCEPROP 1 LAST PATH I145
J 0
(-9150 2125);
DISPLAY 0.978723 (-9150 2125);
PAINT WHITE (-9150 2125);
DISPLAY INVISIBLE (-9150 2125);
FORCEPROP 2 LAST ROOM PVNN_PCH_STBY
J 0
(-9150 2125);
DISPLAY 1.361702 (-9150 2125);
PAINT ORANGE (-9150 2125);
DISPLAY INVISIBLE (-9150 2125);
FORCEPROP 2 LAST CDS_LOCATION C8A8
J 0
(-9150 2075);
DISPLAY 0.617021 (-9150 2075);
PAINT AQUA (-9150 2075);
DISPLAY INVISIBLE (-9150 2075);
FORCEPROP 2 LAST CDS_SEC 1
J 0
(-9150 2125);
PAINT ORANGE (-9150 2125);
DISPLAY INVISIBLE (-9150 2125);
FORCEPROP 2 LAST SEC_TYPE 0402V
J 0
(-9150 2175);
DISPLAY 1.021277 (-9150 2175);
PAINT ORANGE (-9150 2175);
DISPLAY INVISIBLE (-9150 2175);
FORCEPROP 2 LAST SEC 1
J 0
(-9150 2175);
DISPLAY 0.680851 (-9150 2175);
PAINT MONO (-9150 2175);
DISPLAY INVISIBLE (-9150 2175);
FORCEADD GND..1
(-9200 1775);
FORCEPROP 3 LASTPIN (-9200 1825) SIG_NAME GND\g
J 0
(-9190 1835);
DISPLAY 0.659574 (-9190 1835);
PAINT MONO (-9190 1835);
DISPLAY INVISIBLE (-9190 1835);
FORCEPROP 1 LAST HDL_POWER GND
J 0
(-9200 1925);
DISPLAY 1.170213 (-9200 1925);
PAINT GREEN (-9200 1925);
DISPLAY INVISIBLE (-9200 1925);
FORCEPROP 1 LAST BODY_TYPE PLUMBING
J 0
(-9245 1732);
DISPLAY 0.340426 (-9245 1732);
PAINT GREEN (-9245 1732);
DISPLAY INVISIBLE (-9245 1732);
FORCEPROP 2 LAST ROOM PVNN_PCH_STBY
J 0
(-9775 1850);
DISPLAY 1.361702 (-9775 1850);
PAINT ORANGE (-9775 1850);
DISPLAY INVISIBLE (-9775 1850);
FORCEPROP 1 LAST SIZE 1B
J 0
(-9125 1725);
DISPLAY 1.170213 (-9125 1725);
PAINT AQUA (-9125 1725);
DISPLAY INVISIBLE (-9125 1725);
FORCEPROP 1 LAST VOLTAGE 0
J 0
(-9200 1775);
PAINT SKYBLUE (-9200 1775);
DISPLAY INVISIBLE (-9200 1775);
FORCEPROP 2 LAST CDS_LIB mstr_symbols
J 0
(-9200 1775);
PAINT ORANGE (-9200 1775);
DISPLAY INVISIBLE (-9200 1775);
FORCEPROP 1 LAST PATH I146
J 0
(-9125 1775);
DISPLAY 0.872340 (-9125 1775);
PAINT AQUA (-9125 1775);
DISPLAY INVISIBLE (-9125 1775);
FORCEADD RES..1
(-7100 4500);
FORCEPROP 1 LAST LOCATION R2L16
J 0
(-7150 4550);
DISPLAY 0.617021 (-7150 4550);
PAINT AQUA (-7150 4550);
FORCEPROP 1 LAST PACK_TYPE 0402
J 0
(-7150 4300);
DISPLAY 0.617021 (-7150 4300);
PAINT SKYBLUE (-7150 4300);
FORCEPROP 1 LAST WATTAGE 1/16W
J 2
(-7125 4350);
DISPLAY 0.617021 (-7125 4350);
PAINT SKYBLUE (-7125 4350);
FORCEPROP 1 LAST TOLERANCE 1.0%
J 0
(-7100 4400);
DISPLAY 0.617021 (-7100 4400);
PAINT SKYBLUE (-7100 4400);
FORCEPROP 1 LAST MATERIAL CHIP
J 0
(-7100 4350);
DISPLAY 0.617021 (-7100 4350);
PAINT SKYBLUE (-7100 4350);
FORCEPROP 1 LASTPIN (-7000 4500) $PN 2
J 0
(-7038 4512);
DISPLAY 0.617021 (-7038 4512);
PAINT ORANGE (-7038 4512);
FORCEPROP 1 LAST VALUE 22.1
J 2
(-7125 4400);
DISPLAY 0.617021 (-7125 4400);
PAINT SKYBLUE (-7125 4400);
FORCEPROP 1 LASTPIN (-7200 4500) $PN 1
J 0
(-7188 4512);
DISPLAY 0.617021 (-7188 4512);
PAINT ORANGE (-7188 4512);
FORCEPROP 1 LAST PART_NUMBER G21796-250
J 0
(-7150 4600);
DISPLAY 0.617021 (-7150 4600);
PAINT BLUE (-7150 4600);
FORCEPROP 2 LAST CDS_LIB mstr_discrete
J 0
(-7100 4500);
PAINT MONO (-7100 4500);
DISPLAY INVISIBLE (-7100 4500);
FORCEPROP 2 LAST CDS_LOCATION R2L16
J 0
(-7150 4550);
DISPLAY 0.617021 (-7150 4550);
PAINT AQUA (-7150 4550);
DISPLAY INVISIBLE (-7150 4550);
FORCEPROP 2 LAST ROOM PVNN_PCH_STBY
J 0
(-7150 4600);
DISPLAY 1.361702 (-7150 4600);
PAINT ORANGE (-7150 4600);
DISPLAY INVISIBLE (-7150 4600);
FORCEPROP 2 LAST SEC_TYPE 0402
J 0
(-7150 4700);
DISPLAY 1.021277 (-7150 4700);
PAINT ORANGE (-7150 4700);
DISPLAY INVISIBLE (-7150 4700);
FORCEPROP 2 LAST SEC 1
J 0
(-7150 4700);
DISPLAY 0.680851 (-7150 4700);
PAINT MONO (-7150 4700);
DISPLAY INVISIBLE (-7150 4700);
FORCEPROP 1 LAST PATH I147
J 0
(-7150 4650);
DISPLAY 0.978723 (-7150 4650);
PAINT WHITE (-7150 4650);
DISPLAY INVISIBLE (-7150 4650);
FORCEADD RES..2
(-8400 4950);
FORCEPROP 1 LAST PACK_TYPE 0402
J 0
(-8360 4775);
DISPLAY 0.617021 (-8360 4775);
PAINT SKYBLUE (-8360 4775);
FORCEPROP 1 LAST PART_NUMBER G21796-311
J 0
(-8360 4825);
DISPLAY 0.617021 (-8360 4825);
PAINT BLUE (-8360 4825);
FORCEPROP 1 LAST MATERIAL EMPTY
J 0
(-8360 4875);
DISPLAY 0.617021 (-8360 4875);
PAINT RED (-8360 4875);
FORCEPROP 1 LASTPIN (-8400 4850) $PN 2
J 0
(-8395 4860);
DISPLAY 0.617021 (-8395 4860);
PAINT ORANGE (-8395 4860);
FORCEPROP 1 LASTPIN (-8400 5050) $PN 1
J 0
(-8395 5012);
DISPLAY 0.617021 (-8395 5012);
PAINT ORANGE (-8395 5012);
FORCEPROP 1 LAST LOCATION R2L24
J 0
(-8355 5075);
DISPLAY 0.617021 (-8355 5075);
PAINT AQUA (-8355 5075);
FORCEPROP 1 LAST TOLERANCE 1.0%
J 0
(-8355 4975);
DISPLAY 0.617021 (-8355 4975);
PAINT SKYBLUE (-8355 4975);
FORCEPROP 1 LAST WATTAGE 1/16W
J 0
(-8360 4925);
DISPLAY 0.617021 (-8360 4925);
PAINT SKYBLUE (-8360 4925);
FORCEPROP 1 LAST VALUE 2.26K
J 0
(-8355 5025);
DISPLAY 0.617021 (-8355 5025);
PAINT SKYBLUE (-8355 5025);
FORCEPROP 2 LAST ROOM PVNN_PCH_STBY
J 0
(-8350 4925);
DISPLAY 1.361702 (-8350 4925);
PAINT ORANGE (-8350 4925);
DISPLAY INVISIBLE (-8350 4925);
FORCEPROP 2 LAST CDS_LIB mstr_discrete
J 0
(-8400 4950);
PAINT ORANGE (-8400 4950);
DISPLAY INVISIBLE (-8400 4950);
FORCEPROP 1 LAST PATH I148
J 0
(-8350 5125);
DISPLAY 0.978723 (-8350 5125);
PAINT WHITE (-8350 5125);
DISPLAY INVISIBLE (-8350 5125);
FORCEPROP 2 LAST SEC 1
J 0
(-8350 5200);
DISPLAY 0.680851 (-8350 5200);
PAINT MONO (-8350 5200);
DISPLAY INVISIBLE (-8350 5200);
FORCEPROP 2 LAST SEC_TYPE 0402
J 0
(-8350 5200);
DISPLAY 1.021277 (-8350 5200);
PAINT ORANGE (-8350 5200);
DISPLAY INVISIBLE (-8350 5200);
FORCEADD RES..2
(-9100 4950);
FORCEPROP 1 LAST PACK_TYPE 0402
J 0
(-9060 4775);
DISPLAY 0.617021 (-9060 4775);
PAINT SKYBLUE (-9060 4775);
FORCEPROP 1 LAST MATERIAL CHIP
J 0
(-9060 4875);
DISPLAY 0.617021 (-9060 4875);
PAINT SKYBLUE (-9060 4875);
FORCEPROP 1 LASTPIN (-9100 4850) $PN 2
J 0
(-9095 4860);
DISPLAY 0.617021 (-9095 4860);
PAINT ORANGE (-9095 4860);
FORCEPROP 1 LASTPIN (-9100 5050) $PN 1
J 0
(-9095 5012);
DISPLAY 0.617021 (-9095 5012);
PAINT ORANGE (-9095 5012);
FORCEPROP 1 LAST WATTAGE 1/16W
J 0
(-9060 4925);
DISPLAY 0.617021 (-9060 4925);
PAINT SKYBLUE (-9060 4925);
FORCEPROP 1 LAST TOLERANCE 1%
J 0
(-9055 4975);
DISPLAY 0.617021 (-9055 4975);
PAINT SKYBLUE (-9055 4975);
FORCEPROP 1 LAST VALUE 1.00K
J 0
(-9055 5025);
DISPLAY 0.617021 (-9055 5025);
PAINT SKYBLUE (-9055 5025);
FORCEPROP 1 LAST LOCATION R8A6
J 0
(-9055 5075);
DISPLAY 0.617021 (-9055 5075);
PAINT AQUA (-9055 5075);
FORCEPROP 1 LAST PART_NUMBER G21796-026
J 0
(-9060 4825);
DISPLAY 0.617021 (-9060 4825);
PAINT BLUE (-9060 4825);
FORCEPROP 1 LAST PATH I149
J 0
(-9050 5125);
DISPLAY 0.978723 (-9050 5125);
PAINT WHITE (-9050 5125);
DISPLAY INVISIBLE (-9050 5125);
FORCEPROP 2 LAST SEC_TYPE 0402
J 0
(-9050 5175);
DISPLAY 1.021277 (-9050 5175);
PAINT ORANGE (-9050 5175);
DISPLAY INVISIBLE (-9050 5175);
FORCEPROP 2 LAST ROOM PVNN_PCH_STBY
J 0
(-9050 5125);
DISPLAY 1.361702 (-9050 5125);
PAINT ORANGE (-9050 5125);
DISPLAY INVISIBLE (-9050 5125);
FORCEPROP 0 LAST SEC 1
J 0
(-9050 5125);
DISPLAY 0.680851 (-9050 5125);
PAINT MONO (-9050 5125);
DISPLAY INVISIBLE (-9050 5125);
FORCEPROP 2 LAST CDS_LIB mstr_discrete
J 0
(-9100 4950);
PAINT ORANGE (-9100 4950);
DISPLAY INVISIBLE (-9100 4950);
FORCEPROP 2 LAST CDS_LOCATION R8A6
J 0
(-9055 5075);
DISPLAY 0.617021 (-9055 5075);
PAINT AQUA (-9055 5075);
DISPLAY INVISIBLE (-9055 5075);
FORCEADD CAP_A..1
(-9750 5075);
FORCEPROP 1 LAST LOCATION C2L8
J 0
(-9700 5175);
DISPLAY 0.617021 (-9700 5175);
PAINT AQUA (-9700 5175);
FORCEPROP 1 LASTPIN (-9750 4975) $PN 2
J 0
(-9740 4955);
DISPLAY 0.617021 (-9740 4955);
PAINT ORANGE (-9740 4955);
FORCEPROP 1 LASTPIN (-9750 5175) $PN 1
J 0
(-9740 5155);
DISPLAY 0.617021 (-9740 5155);
PAINT ORANGE (-9740 5155);
FORCEPROP 1 LAST PART_NUMBER D97712-004
J 0
(-9700 4925);
DISPLAY 0.617021 (-9700 4925);
PAINT BLUE (-9700 4925);
FORCEPROP 1 LAST VOLTAGE 6.3V
J 0
(-9700 5075);
DISPLAY 0.617021 (-9700 5075);
PAINT SKYBLUE (-9700 5075);
FORCEPROP 1 LAST VALUE 1.0UF
J 0
(-9700 5125);
DISPLAY 0.617021 (-9700 5125);
PAINT SKYBLUE (-9700 5125);
FORCEPROP 1 LAST TOLERANCE 10%
J 0
(-9700 5025);
DISPLAY 0.617021 (-9700 5025);
PAINT SKYBLUE (-9700 5025);
FORCEPROP 1 LAST MATERIAL X6S
J 0
(-9700 4975);
DISPLAY 0.617021 (-9700 4975);
PAINT SKYBLUE (-9700 4975);
FORCEPROP 1 LAST PACK_TYPE 0402V
J 0
(-9700 4875);
DISPLAY 0.617021 (-9700 4875);
PAINT SKYBLUE (-9700 4875);
FORCEPROP 2 LAST CDS_LIB dev_discrete
J 0
(-9750 5075);
PAINT ORANGE (-9750 5075);
DISPLAY INVISIBLE (-9750 5075);
FORCEPROP 2 LAST ROOM PVNN_PCH_STBY
J 0
(-9700 5225);
DISPLAY 1.361702 (-9700 5225);
PAINT ORANGE (-9700 5225);
DISPLAY INVISIBLE (-9700 5225);
FORCEPROP 1 LAST PATH I151
J 0
(-9700 5225);
DISPLAY 0.978723 (-9700 5225);
PAINT WHITE (-9700 5225);
DISPLAY INVISIBLE (-9700 5225);
FORCEPROP 2 LAST SEC 1
J 0
(-9700 5275);
DISPLAY 0.680851 (-9700 5275);
PAINT MONO (-9700 5275);
DISPLAY INVISIBLE (-9700 5275);
FORCEPROP 2 LAST SEC_TYPE 0402V
J 0
(-9700 5275);
DISPLAY 1.021277 (-9700 5275);
PAINT ORANGE (-9700 5275);
DISPLAY INVISIBLE (-9700 5275);
FORCEPROP 2 LAST CDS_LOCATION C2L8
J 0
(-9700 5175);
DISPLAY 0.617021 (-9700 5175);
PAINT AQUA (-9700 5175);
DISPLAY INVISIBLE (-9700 5175);
FORCEPROP 2 LAST CDS_SEC 1
J 0
(-9700 5225);
PAINT ORANGE (-9700 5225);
DISPLAY INVISIBLE (-9700 5225);
FORCEADD GND..1
(-9750 4875);
FORCEPROP 3 LASTPIN (-9750 4925) SIG_NAME GND\g
J 0
(-9740 4935);
DISPLAY 0.659574 (-9740 4935);
PAINT MONO (-9740 4935);
DISPLAY INVISIBLE (-9740 4935);
FORCEPROP 1 LAST HDL_POWER GND
J 0
(-9750 5025);
DISPLAY 1.170213 (-9750 5025);
PAINT GREEN (-9750 5025);
DISPLAY INVISIBLE (-9750 5025);
FORCEPROP 1 LAST BODY_TYPE PLUMBING
J 0
(-9795 4832);
DISPLAY 0.340426 (-9795 4832);
PAINT GREEN (-9795 4832);
DISPLAY INVISIBLE (-9795 4832);
FORCEPROP 2 LAST ROOM PVNN_PCH_STBY
J 0
(-10325 4950);
DISPLAY 1.361702 (-10325 4950);
PAINT ORANGE (-10325 4950);
DISPLAY INVISIBLE (-10325 4950);
FORCEPROP 1 LAST VOLTAGE 0
J 0
(-9750 4875);
PAINT SKYBLUE (-9750 4875);
DISPLAY INVISIBLE (-9750 4875);
FORCEPROP 2 LAST CDS_LIB mstr_symbols
J 0
(-9750 4875);
PAINT ORANGE (-9750 4875);
DISPLAY INVISIBLE (-9750 4875);
FORCEPROP 1 LAST PATH I152
J 0
(-9675 4875);
DISPLAY 0.872340 (-9675 4875);
PAINT AQUA (-9675 4875);
DISPLAY INVISIBLE (-9675 4875);
FORCEPROP 1 LAST SIZE 1B
J 0
(-9675 4825);
DISPLAY 1.170213 (-9675 4825);
PAINT AQUA (-9675 4825);
DISPLAY INVISIBLE (-9675 4825);
FORCEADD CAP..1
(-12475 2075);
FORCEPROP 1 LAST TOLERANCE 10%
J 0
(-12250 2125);
DISPLAY 0.617021 (-12250 2125);
PAINT SKYBLUE (-12250 2125);
FORCEPROP 1 LAST LOCATION C2L2
J 0
(-12425 2175);
DISPLAY 0.617021 (-12425 2175);
PAINT AQUA (-12425 2175);
FORCEPROP 1 LASTPIN (-12475 1975) $PN 2
J 0
(-12465 1955);
DISPLAY 0.617021 (-12465 1955);
PAINT ORANGE (-12465 1955);
FORCEPROP 1 LAST MATERIAL X7R
J 0
(-12300 2075);
DISPLAY 0.617021 (-12300 2075);
PAINT SKYBLUE (-12300 2075);
FORCEPROP 1 LAST PACK_TYPE 0402LF
J 0
(-12425 1975);
DISPLAY 0.617021 (-12425 1975);
PAINT SKYBLUE (-12425 1975);
FORCEPROP 1 LAST PART_NUMBER A36096-050
J 0
(-12425 2025);
DISPLAY 0.617021 (-12425 2025);
PAINT BLUE (-12425 2025);
FORCEPROP 1 LAST VOLTAGE 50V
J 0
(-12425 2075);
DISPLAY 0.617021 (-12425 2075);
PAINT SKYBLUE (-12425 2075);
FORCEPROP 1 LAST VALUE 220PF
J 0
(-12425 2125);
DISPLAY 0.617021 (-12425 2125);
PAINT SKYBLUE (-12425 2125);
FORCEPROP 1 LASTPIN (-12475 2175) $PN 1
J 0
(-12465 2155);
DISPLAY 0.617021 (-12465 2155);
PAINT ORANGE (-12465 2155);
FORCEPROP 2 LAST CDS_LIB mstr_discrete
J 0
(-12475 2075);
PAINT ORANGE (-12475 2075);
DISPLAY INVISIBLE (-12475 2075);
FORCEPROP 2 LAST CDS_LOCATION C2L2
J 0
(-12425 2175);
DISPLAY 0.617021 (-12425 2175);
PAINT AQUA (-12425 2175);
DISPLAY INVISIBLE (-12425 2175);
FORCEPROP 2 LAST ROOM PVNN_PCH_STBY
J 0
(-12425 2225);
DISPLAY 1.361702 (-12425 2225);
PAINT ORANGE (-12425 2225);
DISPLAY INVISIBLE (-12425 2225);
FORCEPROP 1 LAST PATH I153
J 0
(-12425 2225);
DISPLAY 0.978723 (-12425 2225);
PAINT WHITE (-12425 2225);
DISPLAY INVISIBLE (-12425 2225);
FORCEPROP 2 LAST NO_XNET_CONNECTION 1
J 0
(-12425 2275);
PAINT MONO (-12425 2275);
DISPLAY INVISIBLE (-12425 2275);
FORCEPROP 2 LAST SEC 1
J 0
(-12425 2300);
DISPLAY 0.680851 (-12425 2300);
PAINT MONO (-12425 2300);
DISPLAY INVISIBLE (-12425 2300);
FORCEPROP 2 LAST SEC_TYPE 0402LF
J 0
(-12425 2300);
DISPLAY 1.021277 (-12425 2300);
PAINT ORANGE (-12425 2300);
DISPLAY INVISIBLE (-12425 2300);
FORCEADD RES..1
(-12675 2225);
FORCEPROP 1 LAST LOCATION R2L8
J 0
(-12725 2275);
DISPLAY 0.617021 (-12725 2275);
PAINT AQUA (-12725 2275);
FORCEPROP 1 LAST WATTAGE 1/10W
J 2
(-12675 2075);
DISPLAY 0.617021 (-12675 2075);
PAINT SKYBLUE (-12675 2075);
FORCEPROP 1 LASTPIN (-12775 2225) $PN 1
J 0
(-12763 2237);
DISPLAY 0.617021 (-12763 2237);
PAINT ORANGE (-12763 2237);
FORCEPROP 1 LAST VALUE 10.0
J 2
(-12775 2125);
DISPLAY 0.617021 (-12775 2125);
PAINT SKYBLUE (-12775 2125);
FORCEPROP 1 LAST TOLERANCE 1%
J 0
(-12750 2125);
DISPLAY 0.617021 (-12750 2125);
PAINT SKYBLUE (-12750 2125);
FORCEPROP 1 LAST MATERIAL CHIP
J 0
(-12650 2075);
DISPLAY 0.617021 (-12650 2075);
PAINT SKYBLUE (-12650 2075);
FORCEPROP 1 LAST PACK_TYPE 0603
J 0
(-12650 2125);
DISPLAY 0.617021 (-12650 2125);
PAINT SKYBLUE (-12650 2125);
FORCEPROP 1 LAST PART_NUMBER G22026-041
J 0
(-12825 2175);
DISPLAY 0.617021 (-12825 2175);
PAINT BLUE (-12825 2175);
FORCEPROP 1 LASTPIN (-12575 2225) $PN 2
J 0
(-12613 2237);
DISPLAY 0.617021 (-12613 2237);
PAINT ORANGE (-12613 2237);
FORCEPROP 2 LAST CDS_LIB mstr_discrete
J 0
(-12675 2225);
PAINT ORANGE (-12675 2225);
DISPLAY INVISIBLE (-12675 2225);
FORCEPROP 2 LAST CDS_LOCATION R2L8
J 0
(-12725 2275);
DISPLAY 0.617021 (-12725 2275);
PAINT AQUA (-12725 2275);
DISPLAY INVISIBLE (-12725 2275);
FORCEPROP 2 LAST SEC_TYPE 0603
J 0
(-12725 2450);
DISPLAY 1.021277 (-12725 2450);
PAINT ORANGE (-12725 2450);
DISPLAY INVISIBLE (-12725 2450);
FORCEPROP 2 LAST SEC 1
J 0
(-12725 2450);
DISPLAY 0.680851 (-12725 2450);
PAINT MONO (-12725 2450);
DISPLAY INVISIBLE (-12725 2450);
FORCEPROP 1 LAST PATH I154
J 0
(-12725 2375);
DISPLAY 0.978723 (-12725 2375);
PAINT WHITE (-12725 2375);
DISPLAY INVISIBLE (-12725 2375);
FORCEPROP 2 LAST ROOM PVNN_PCH_STBY
J 0
(-12600 2325);
DISPLAY 1.361702 (-12600 2325);
PAINT ORANGE (-12600 2325);
DISPLAY INVISIBLE (-12600 2325);
FORCEADD GND..1
(-8900 2800);
FORCEPROP 3 LASTPIN (-8900 2850) SIG_NAME GND\g
J 0
(-8890 2860);
DISPLAY 0.659574 (-8890 2860);
PAINT MONO (-8890 2860);
DISPLAY INVISIBLE (-8890 2860);
FORCEPROP 1 LAST HDL_POWER GND
J 0
(-8900 2950);
DISPLAY 1.170213 (-8900 2950);
PAINT GREEN (-8900 2950);
DISPLAY INVISIBLE (-8900 2950);
FORCEPROP 1 LAST BODY_TYPE PLUMBING
J 0
(-8945 2757);
DISPLAY 0.340426 (-8945 2757);
PAINT GREEN (-8945 2757);
DISPLAY INVISIBLE (-8945 2757);
FORCEPROP 2 LAST ROOM PVNN_PCH_STBY
J 0
(-9475 2875);
DISPLAY 1.361702 (-9475 2875);
PAINT ORANGE (-9475 2875);
DISPLAY INVISIBLE (-9475 2875);
FORCEPROP 1 LAST SIZE 1B
J 0
(-8825 2750);
DISPLAY 1.170213 (-8825 2750);
PAINT AQUA (-8825 2750);
DISPLAY INVISIBLE (-8825 2750);
FORCEPROP 1 LAST PATH I155
J 0
(-8825 2800);
DISPLAY 0.872340 (-8825 2800);
PAINT AQUA (-8825 2800);
DISPLAY INVISIBLE (-8825 2800);
FORCEPROP 2 LAST CDS_LIB mstr_symbols
J 0
(-8900 2800);
PAINT ORANGE (-8900 2800);
DISPLAY INVISIBLE (-8900 2800);
FORCEPROP 1 LAST VOLTAGE 0
J 0
(-8900 2800);
PAINT SKYBLUE (-8900 2800);
DISPLAY INVISIBLE (-8900 2800);
FORCEADD OFFPAGE..1
(-13450 2225);
FORCEPROP 2 LAST $XR0 236 
J 0
(-13732 2225);
DISPLAY 0.638298 (-13732 2225);
PAINT MONO (-13732 2225);
FORCEPROP 2 LAST CDS_LIB mstr_standard
J 0
(-13450 2225);
PAINT ORANGE (-13450 2225);
DISPLAY INVISIBLE (-13450 2225);
FORCEPROP 2 LAST PATH I156
J 0
(-13700 2275);
DISPLAY 1.021277 (-13700 2275);
PAINT ORANGE (-13700 2275);
DISPLAY INVISIBLE (-13700 2275);
FORCEPROP 2 LAST ROOM PVNN_PCH_STBY
J 0
(-14000 2300);
DISPLAY 1.361702 (-14000 2300);
PAINT ORANGE (-14000 2300);
DISPLAY INVISIBLE (-14000 2300);
FORCEPROP 1 LAST OFFPAGE TRUE
J 0
(-13125 2100);
DISPLAY 1.170213 (-13125 2100);
PAINT GREEN (-13125 2100);
DISPLAY INVISIBLE (-13125 2100);
FORCEPROP 1 LAST COMMENT_BODY TRUE
J 0
(-13325 2125);
DISPLAY 1.170213 (-13325 2125);
PAINT GREEN (-13325 2125);
DISPLAY INVISIBLE (-13325 2125);
FORCEADD OFFPAGE..1
(-13425 1950);
FORCEPROP 2 LAST $XR0 236 
J 0
(-13677 1950);
DISPLAY 0.638298 (-13677 1950);
PAINT MONO (-13677 1950);
FORCEPROP 1 LAST COMMENT_BODY TRUE
J 0
(-13300 1850);
DISPLAY 1.170213 (-13300 1850);
PAINT GREEN (-13300 1850);
DISPLAY INVISIBLE (-13300 1850);
FORCEPROP 1 LAST OFFPAGE TRUE
J 0
(-13100 1825);
DISPLAY 1.170213 (-13100 1825);
PAINT GREEN (-13100 1825);
DISPLAY INVISIBLE (-13100 1825);
FORCEPROP 2 LAST PATH I157
J 0
(-13675 2000);
DISPLAY 1.021277 (-13675 2000);
PAINT ORANGE (-13675 2000);
DISPLAY INVISIBLE (-13675 2000);
FORCEPROP 2 LAST CDS_LIB mstr_standard
J 0
(-13425 1950);
PAINT ORANGE (-13425 1950);
DISPLAY INVISIBLE (-13425 1950);
FORCEPROP 2 LAST ROOM PVNN_PCH_STBY
J 0
(-13975 2025);
DISPLAY 1.361702 (-13975 2025);
PAINT ORANGE (-13975 2025);
DISPLAY INVISIBLE (-13975 2025);
FORCEADD P3V3_STBY..1
(-10450 5750);
FORCEPROP 3 LASTPIN (-10450 5700) SIG_NAME P3V3_STBY\g
J 0
(-10440 5710);
DISPLAY 0.659574 (-10440 5710);
PAINT MONO (-10440 5710);
DISPLAY INVISIBLE (-10440 5710);
FORCEPROP 1 LAST HDL_POWER P3V3_STBY
J 0
(-10750 5625);
DISPLAY 0.872340 (-10750 5625);
PAINT ORANGE (-10750 5625);
DISPLAY INVISIBLE (-10750 5625);
FORCEPROP 1 LAST BODY_TYPE PLUMBING
J 0
(-10495 5707);
DISPLAY 0.340426 (-10495 5707);
PAINT GREEN (-10495 5707);
DISPLAY INVISIBLE (-10495 5707);
FORCEPROP 1 LAST PATH I158
J 0
(-10405 5752);
DISPLAY 0.340426 (-10405 5752);
PAINT GREEN (-10405 5752);
DISPLAY INVISIBLE (-10405 5752);
FORCEPROP 2 LAST CDS_LIB mstr_symbols
J 0
(-10450 5750);
PAINT ORANGE (-10450 5750);
DISPLAY INVISIBLE (-10450 5750);
FORCEPROP 1 LAST SIZE 1B
J 0
(-10405 5772);
DISPLAY 0.340426 (-10405 5772);
PAINT GREEN (-10405 5772);
DISPLAY INVISIBLE (-10405 5772);
FORCEPROP 1 LAST VOLTAGE 3.3V
J 0
(-10495 5707);
DISPLAY 0.340426 (-10495 5707);
PAINT SKYBLUE (-10495 5707);
DISPLAY INVISIBLE (-10495 5707);
FORCEADD RES..2
(-10450 5425);
FORCEPROP 1 LAST WATTAGE 1/16W
J 0
(-10410 5400);
DISPLAY 0.617021 (-10410 5400);
PAINT SKYBLUE (-10410 5400);
FORCEPROP 1 LAST MATERIAL CHIP
J 0
(-10410 5350);
DISPLAY 0.617021 (-10410 5350);
PAINT SKYBLUE (-10410 5350);
FORCEPROP 1 LAST PACK_TYPE 0402
J 0
(-10410 5250);
DISPLAY 0.617021 (-10410 5250);
PAINT SKYBLUE (-10410 5250);
FORCEPROP 1 LASTPIN (-10450 5325) $PN 2
J 0
(-10445 5335);
DISPLAY 0.617021 (-10445 5335);
PAINT ORANGE (-10445 5335);
FORCEPROP 1 LASTPIN (-10450 5525) $PN 1
J 0
(-10445 5487);
DISPLAY 0.617021 (-10445 5487);
PAINT ORANGE (-10445 5487);
FORCEPROP 1 LAST LOCATION R2L14
J 0
(-10405 5550);
DISPLAY 0.617021 (-10405 5550);
PAINT AQUA (-10405 5550);
FORCEPROP 1 LAST VALUE 0.0
J 0
(-10405 5500);
DISPLAY 0.617021 (-10405 5500);
PAINT SKYBLUE (-10405 5500);
FORCEPROP 1 LAST TOLERANCE 5%
J 0
(-10405 5450);
DISPLAY 0.617021 (-10405 5450);
PAINT SKYBLUE (-10405 5450);
FORCEPROP 1 LAST PART_NUMBER G21497-005
J 0
(-10410 5300);
DISPLAY 0.617021 (-10410 5300);
PAINT BLUE (-10410 5300);
FORCEPROP 2 LAST CDS_LIB mstr_discrete
J 0
(-10450 5425);
PAINT ORANGE (-10450 5425);
DISPLAY INVISIBLE (-10450 5425);
FORCEPROP 2 LAST CDS_LOCATION R2L14
J 0
(-10405 5550);
DISPLAY 0.617021 (-10405 5550);
PAINT AQUA (-10405 5550);
DISPLAY INVISIBLE (-10405 5550);
FORCEPROP 0 LAST SEC 1
J 0
(-10400 5600);
DISPLAY 0.680851 (-10400 5600);
PAINT MONO (-10400 5600);
DISPLAY INVISIBLE (-10400 5600);
FORCEPROP 2 LAST ROOM PVNN_PCH_STBY
J 0
(-10400 5600);
DISPLAY 1.361702 (-10400 5600);
PAINT ORANGE (-10400 5600);
DISPLAY INVISIBLE (-10400 5600);
FORCEPROP 1 LAST PATH I159
J 0
(-10400 5600);
DISPLAY 0.978723 (-10400 5600);
PAINT WHITE (-10400 5600);
DISPLAY INVISIBLE (-10400 5600);
FORCEPROP 2 LAST SEC_TYPE 0402
J 0
(-10400 5650);
DISPLAY 1.021277 (-10400 5650);
PAINT ORANGE (-10400 5650);
DISPLAY INVISIBLE (-10400 5650);
FORCEADD RES..2
(-12325 5500);
FORCEPROP 1 LAST WATTAGE 1/16W
J 0
(-12285 5475);
DISPLAY 0.617021 (-12285 5475);
PAINT SKYBLUE (-12285 5475);
FORCEPROP 1 LASTPIN (-12325 5400) $PN 2
J 0
(-12320 5410);
DISPLAY 0.617021 (-12320 5410);
PAINT ORANGE (-12320 5410);
FORCEPROP 1 LASTPIN (-12325 5600) $PN 1
J 0
(-12320 5562);
DISPLAY 0.617021 (-12320 5562);
PAINT ORANGE (-12320 5562);
FORCEPROP 1 LAST PACK_TYPE 0402
J 0
(-12285 5325);
DISPLAY 0.617021 (-12285 5325);
PAINT SKYBLUE (-12285 5325);
FORCEPROP 1 LAST LOCATION R8A4
J 0
(-12505 5500);
DISPLAY 0.617021 (-12505 5500);
PAINT AQUA (-12505 5500);
FORCEPROP 1 LAST TOLERANCE 1%
J 0
(-12280 5525);
DISPLAY 0.617021 (-12280 5525);
PAINT SKYBLUE (-12280 5525);
FORCEPROP 1 LAST VALUE 100.0K
J 0
(-12280 5575);
DISPLAY 0.617021 (-12280 5575);
PAINT SKYBLUE (-12280 5575);
FORCEPROP 1 LAST MATERIAL CHIP
J 0
(-12285 5425);
DISPLAY 0.617021 (-12285 5425);
PAINT SKYBLUE (-12285 5425);
FORCEPROP 1 LAST PART_NUMBER G21796-160
J 0
(-12285 5375);
DISPLAY 0.617021 (-12285 5375);
PAINT BLUE (-12285 5375);
FORCEPROP 2 LAST CDS_LOCATION R8A4
J 0
(-12505 5500);
DISPLAY 0.617021 (-12505 5500);
PAINT AQUA (-12505 5500);
DISPLAY INVISIBLE (-12505 5500);
FORCEPROP 2 LAST CDS_LIB mstr_discrete
J 0
(-12325 5500);
PAINT ORANGE (-12325 5500);
DISPLAY INVISIBLE (-12325 5500);
FORCEPROP 2 LAST ROOM PVNN_PCH_STBY
J 0
(-12275 5675);
DISPLAY 1.361702 (-12275 5675);
PAINT ORANGE (-12275 5675);
DISPLAY INVISIBLE (-12275 5675);
FORCEPROP 1 LAST PATH I165
J 0
(-12275 5675);
DISPLAY 0.978723 (-12275 5675);
PAINT WHITE (-12275 5675);
DISPLAY INVISIBLE (-12275 5675);
FORCEPROP 2 LAST SEC 1
J 0
(-12275 5725);
DISPLAY 0.680851 (-12275 5725);
PAINT MONO (-12275 5725);
DISPLAY INVISIBLE (-12275 5725);
FORCEPROP 2 LAST SEC_TYPE 0402
J 0
(-12275 5725);
DISPLAY 1.021277 (-12275 5725);
PAINT ORANGE (-12275 5725);
DISPLAY INVISIBLE (-12275 5725);
FORCEADD RES..2
(-12325 5175);
FORCEPROP 1 LAST PACK_TYPE 0402
J 0
(-12285 5000);
DISPLAY 0.617021 (-12285 5000);
PAINT SKYBLUE (-12285 5000);
FORCEPROP 1 LAST PART_NUMBER G21796-003
J 0
(-12285 5050);
DISPLAY 0.617021 (-12285 5050);
PAINT BLUE (-12285 5050);
FORCEPROP 1 LASTPIN (-12325 5075) $PN 2
J 0
(-12320 5085);
DISPLAY 0.617021 (-12320 5085);
PAINT ORANGE (-12320 5085);
FORCEPROP 1 LASTPIN (-12325 5275) $PN 1
J 0
(-12320 5237);
DISPLAY 0.617021 (-12320 5237);
PAINT ORANGE (-12320 5237);
FORCEPROP 1 LAST VALUE 1.5K
J 0
(-12280 5250);
DISPLAY 0.617021 (-12280 5250);
PAINT SKYBLUE (-12280 5250);
FORCEPROP 1 LAST MATERIAL CHIP
J 0
(-12285 5100);
DISPLAY 0.617021 (-12285 5100);
PAINT SKYBLUE (-12285 5100);
FORCEPROP 1 LAST LOCATION R2L10
J 0
(-12155 5250);
DISPLAY 0.617021 (-12155 5250);
PAINT AQUA (-12155 5250);
FORCEPROP 1 LAST TOLERANCE 1%
J 0
(-12280 5200);
DISPLAY 0.617021 (-12280 5200);
PAINT SKYBLUE (-12280 5200);
FORCEPROP 1 LAST WATTAGE 1/16W
J 0
(-12285 5150);
DISPLAY 0.617021 (-12285 5150);
PAINT SKYBLUE (-12285 5150);
FORCEPROP 2 LAST CDS_LOCATION R2L10
J 0
(-12480 5150);
DISPLAY 0.617021 (-12480 5150);
PAINT AQUA (-12480 5150);
DISPLAY INVISIBLE (-12480 5150);
FORCEPROP 2 LAST CDS_LIB mstr_discrete
J 0
(-12325 5175);
PAINT ORANGE (-12325 5175);
DISPLAY INVISIBLE (-12325 5175);
FORCEPROP 2 LAST ROOM PVNN_PCH_STBY
J 0
(-12275 5350);
DISPLAY 1.361702 (-12275 5350);
PAINT ORANGE (-12275 5350);
DISPLAY INVISIBLE (-12275 5350);
FORCEPROP 1 LAST PATH I166
J 0
(-12275 5350);
DISPLAY 0.978723 (-12275 5350);
PAINT WHITE (-12275 5350);
DISPLAY INVISIBLE (-12275 5350);
FORCEPROP 2 LAST SEC 1
J 0
(-12275 5400);
DISPLAY 0.680851 (-12275 5400);
PAINT MONO (-12275 5400);
DISPLAY INVISIBLE (-12275 5400);
FORCEPROP 2 LAST SEC_TYPE 0402
J 0
(-12275 5400);
DISPLAY 1.021277 (-12275 5400);
PAINT ORANGE (-12275 5400);
DISPLAY INVISIBLE (-12275 5400);
FORCEADD OFFPAGE..2
R 2
(-13150 5500);
FORCEPROP 2 LAST $XR0 235 
J 0
(-13405 5500);
DISPLAY 0.638298 (-13405 5500);
PAINT MONO (-13405 5500);
FORCEPROP 2 LAST CDS_LIB mstr_standard
J 2
(-13150 5500);
PAINT ORANGE (-13150 5500);
DISPLAY INVISIBLE (-13150 5500);
FORCEPROP 2 LAST ROOM PVNN_PCH_STBY
J 0
(-13700 5575);
DISPLAY 1.361702 (-13700 5575);
PAINT ORANGE (-13700 5575);
DISPLAY INVISIBLE (-13700 5575);
FORCEPROP 2 LAST PATH I168
J 0
(-13425 5550);
DISPLAY 1.021277 (-13425 5550);
PAINT ORANGE (-13425 5550);
DISPLAY INVISIBLE (-13425 5550);
FORCEPROP 1 LAST OFFPAGE TRUE
J 2
(-13475 5375);
DISPLAY 1.170213 (-13475 5375);
PAINT GREEN (-13475 5375);
DISPLAY INVISIBLE (-13475 5375);
FORCEPROP 1 LAST COMMENT_BODY TRUE
J 2
(-13105 5405);
DISPLAY 1.170213 (-13105 5405);
PAINT GREEN (-13105 5405);
DISPLAY INVISIBLE (-13105 5405);
FORCEADD CAP_A..1
(-10150 5075);
FORCEPROP 1 LAST MATERIAL X7R
J 0
(-10100 4975);
DISPLAY 0.617021 (-10100 4975);
PAINT SKYBLUE (-10100 4975);
FORCEPROP 1 LASTPIN (-10150 4975) $PN 2
J 0
(-10140 4955);
DISPLAY 0.617021 (-10140 4955);
PAINT ORANGE (-10140 4955);
FORCEPROP 1 LASTPIN (-10150 5175) $PN 1
J 0
(-10140 5155);
DISPLAY 0.617021 (-10140 5155);
PAINT ORANGE (-10140 5155);
FORCEPROP 1 LAST TOLERANCE 10%
J 0
(-10100 5025);
DISPLAY 0.617021 (-10100 5025);
PAINT SKYBLUE (-10100 5025);
FORCEPROP 1 LAST VOLTAGE 16V
J 0
(-10100 5075);
DISPLAY 0.617021 (-10100 5075);
PAINT SKYBLUE (-10100 5075);
FORCEPROP 1 LAST VALUE 0.1UF
J 0
(-10100 5125);
DISPLAY 0.617021 (-10100 5125);
PAINT SKYBLUE (-10100 5125);
FORCEPROP 1 LAST LOCATION C2L11
J 0
(-10100 5175);
DISPLAY 0.617021 (-10100 5175);
PAINT AQUA (-10100 5175);
FORCEPROP 1 LAST PACK_TYPE 0402V
J 0
(-10100 4875);
DISPLAY 0.617021 (-10100 4875);
PAINT SKYBLUE (-10100 4875);
FORCEPROP 1 LAST PART_NUMBER A36096-030
J 0
(-10100 4925);
DISPLAY 0.617021 (-10100 4925);
PAINT BLUE (-10100 4925);
FORCEPROP 2 LAST CDS_LIB dev_discrete
J 0
(-10150 5075);
PAINT ORANGE (-10150 5075);
DISPLAY INVISIBLE (-10150 5075);
FORCEPROP 1 LAST PATH I169
J 0
(-10100 5225);
DISPLAY 0.978723 (-10100 5225);
PAINT WHITE (-10100 5225);
DISPLAY INVISIBLE (-10100 5225);
FORCEPROP 2 LAST ROOM PVNN_PCH_STBY
J 0
(-10100 5225);
DISPLAY 1.361702 (-10100 5225);
PAINT ORANGE (-10100 5225);
DISPLAY INVISIBLE (-10100 5225);
FORCEPROP 2 LAST CDS_LOCATION C2L11
J 0
(-10100 5175);
DISPLAY 0.617021 (-10100 5175);
PAINT AQUA (-10100 5175);
DISPLAY INVISIBLE (-10100 5175);
FORCEPROP 2 LAST CDS_SEC 1
J 0
(-10100 5225);
PAINT ORANGE (-10100 5225);
DISPLAY INVISIBLE (-10100 5225);
FORCEPROP 2 LAST SEC_TYPE 0402V
J 0
(-10100 5275);
DISPLAY 1.021277 (-10100 5275);
PAINT ORANGE (-10100 5275);
DISPLAY INVISIBLE (-10100 5275);
FORCEPROP 2 LAST SEC 1
J 0
(-10100 5225);
DISPLAY 0.680851 (-10100 5225);
PAINT MONO (-10100 5225);
DISPLAY INVISIBLE (-10100 5225);
FORCEADD GND..1
(-10150 4875);
FORCEPROP 3 LASTPIN (-10150 4925) SIG_NAME GND\g
J 0
(-10140 4935);
DISPLAY 0.659574 (-10140 4935);
PAINT MONO (-10140 4935);
DISPLAY INVISIBLE (-10140 4935);
FORCEPROP 1 LAST HDL_POWER GND
J 0
(-10150 5025);
DISPLAY 1.170213 (-10150 5025);
PAINT GREEN (-10150 5025);
DISPLAY INVISIBLE (-10150 5025);
FORCEPROP 1 LAST BODY_TYPE PLUMBING
J 0
(-10195 4832);
DISPLAY 0.340426 (-10195 4832);
PAINT GREEN (-10195 4832);
DISPLAY INVISIBLE (-10195 4832);
FORCEPROP 2 LAST ROOM PVNN_PCH_STBY
J 0
(-10725 4950);
DISPLAY 1.361702 (-10725 4950);
PAINT ORANGE (-10725 4950);
DISPLAY INVISIBLE (-10725 4950);
FORCEPROP 1 LAST SIZE 1B
J 0
(-10075 4825);
DISPLAY 1.170213 (-10075 4825);
PAINT AQUA (-10075 4825);
DISPLAY INVISIBLE (-10075 4825);
FORCEPROP 2 LAST CDS_LIB mstr_symbols
J 0
(-10150 4875);
PAINT ORANGE (-10150 4875);
DISPLAY INVISIBLE (-10150 4875);
FORCEPROP 1 LAST VOLTAGE 0
J 0
(-10150 4875);
PAINT SKYBLUE (-10150 4875);
DISPLAY INVISIBLE (-10150 4875);
FORCEPROP 1 LAST PATH I170
J 0
(-10075 4875);
DISPLAY 0.872340 (-10075 4875);
PAINT AQUA (-10075 4875);
DISPLAY INVISIBLE (-10075 4875);
FORCEADD GND..1
(-10750 1850);
FORCEPROP 3 LASTPIN (-10750 1900) SIG_NAME GND\g
J 0
(-10740 1910);
DISPLAY 0.659574 (-10740 1910);
PAINT MONO (-10740 1910);
DISPLAY INVISIBLE (-10740 1910);
FORCEPROP 1 LAST VOLTAGE 0
J 0
(-10750 1850);
PAINT SKYBLUE (-10750 1850);
DISPLAY INVISIBLE (-10750 1850);
FORCEPROP 1 LAST PATH I178
J 0
(-10675 1850);
DISPLAY 0.872340 (-10675 1850);
PAINT AQUA (-10675 1850);
DISPLAY INVISIBLE (-10675 1850);
FORCEPROP 1 LAST SIZE 1B
J 0
(-10675 1800);
DISPLAY 1.170213 (-10675 1800);
PAINT AQUA (-10675 1800);
DISPLAY INVISIBLE (-10675 1800);
FORCEPROP 2 LAST CDS_LIB mstr_symbols
J 0
(-10750 1850);
PAINT ORANGE (-10750 1850);
DISPLAY INVISIBLE (-10750 1850);
FORCEPROP 2 LAST ROOM PVNN_PCH_STBY
J 0
(-11325 1925);
DISPLAY 1.361702 (-11325 1925);
PAINT ORANGE (-11325 1925);
DISPLAY INVISIBLE (-11325 1925);
FORCEPROP 1 LAST BODY_TYPE PLUMBING
J 0
(-10795 1807);
DISPLAY 0.340426 (-10795 1807);
PAINT GREEN (-10795 1807);
DISPLAY INVISIBLE (-10795 1807);
FORCEPROP 1 LAST HDL_POWER GND
J 0
(-10750 2000);
DISPLAY 1.170213 (-10750 2000);
PAINT GREEN (-10750 2000);
DISPLAY INVISIBLE (-10750 2000);
FORCEADD GND..1
(-12325 4925);
FORCEPROP 3 LASTPIN (-12325 4975) SIG_NAME GND\g
J 0
(-12315 4985);
DISPLAY 0.659574 (-12315 4985);
PAINT MONO (-12315 4985);
DISPLAY INVISIBLE (-12315 4985);
FORCEPROP 1 LAST HDL_POWER GND
J 0
(-12325 5075);
DISPLAY 1.170213 (-12325 5075);
PAINT GREEN (-12325 5075);
DISPLAY INVISIBLE (-12325 5075);
FORCEPROP 1 LAST BODY_TYPE PLUMBING
J 0
(-12370 4882);
DISPLAY 0.340426 (-12370 4882);
PAINT GREEN (-12370 4882);
DISPLAY INVISIBLE (-12370 4882);
FORCEPROP 2 LAST ROOM PVNN_PCH_STBY
J 0
(-12900 5000);
DISPLAY 1.361702 (-12900 5000);
PAINT ORANGE (-12900 5000);
DISPLAY INVISIBLE (-12900 5000);
FORCEPROP 1 LAST VOLTAGE 0
J 0
(-12325 4925);
PAINT SKYBLUE (-12325 4925);
DISPLAY INVISIBLE (-12325 4925);
FORCEPROP 2 LAST CDS_LIB mstr_symbols
J 0
(-12325 4925);
PAINT ORANGE (-12325 4925);
DISPLAY INVISIBLE (-12325 4925);
FORCEPROP 1 LAST PATH I181
J 0
(-12250 4925);
DISPLAY 0.872340 (-12250 4925);
PAINT AQUA (-12250 4925);
DISPLAY INVISIBLE (-12250 4925);
FORCEPROP 1 LAST SIZE 1B
J 0
(-12250 4875);
DISPLAY 1.170213 (-12250 4875);
PAINT AQUA (-12250 4875);
DISPLAY INVISIBLE (-12250 4875);
FORCEADD GND..1
(-12750 4975);
FORCEPROP 3 LASTPIN (-12750 5025) SIG_NAME GND\g
J 0
(-12740 5035);
DISPLAY 0.659574 (-12740 5035);
PAINT MONO (-12740 5035);
DISPLAY INVISIBLE (-12740 5035);
FORCEPROP 1 LAST PATH I183
J 0
(-12675 4975);
DISPLAY 0.872340 (-12675 4975);
PAINT AQUA (-12675 4975);
DISPLAY INVISIBLE (-12675 4975);
FORCEPROP 1 LAST SIZE 1B
J 0
(-12675 4925);
DISPLAY 1.170213 (-12675 4925);
PAINT AQUA (-12675 4925);
DISPLAY INVISIBLE (-12675 4925);
FORCEPROP 1 LAST VOLTAGE 0
J 0
(-12750 4975);
PAINT SKYBLUE (-12750 4975);
DISPLAY INVISIBLE (-12750 4975);
FORCEPROP 2 LAST CDS_LIB mstr_symbols
J 0
(-12750 4975);
PAINT ORANGE (-12750 4975);
DISPLAY INVISIBLE (-12750 4975);
FORCEPROP 2 LAST ROOM PVNN_PCH_STBY
J 0
(-13325 5050);
DISPLAY 1.361702 (-13325 5050);
PAINT ORANGE (-13325 5050);
DISPLAY INVISIBLE (-13325 5050);
FORCEPROP 1 LAST BODY_TYPE PLUMBING
J 0
(-12795 4932);
DISPLAY 0.340426 (-12795 4932);
PAINT GREEN (-12795 4932);
DISPLAY INVISIBLE (-12795 4932);
FORCEPROP 1 LAST HDL_POWER GND
J 0
(-12750 5125);
DISPLAY 1.170213 (-12750 5125);
PAINT GREEN (-12750 5125);
DISPLAY INVISIBLE (-12750 5125);
FORCEADD OFFPAGE..1
(-12850 4300);
FORCEPROP 2 LAST $XR0 236 
J 0
(-13132 4300);
DISPLAY 0.638298 (-13132 4300);
PAINT MONO (-13132 4300);
FORCEPROP 2 LAST CDS_LIB mstr_standard
J 0
(-12850 4300);
PAINT ORANGE (-12850 4300);
DISPLAY INVISIBLE (-12850 4300);
FORCEPROP 2 LAST PATH I185
J 0
(-13100 4350);
DISPLAY 1.021277 (-13100 4350);
PAINT ORANGE (-13100 4350);
DISPLAY INVISIBLE (-13100 4350);
FORCEPROP 2 LAST ROOM PVNN_PCH_STBY
J 0
(-13400 4375);
DISPLAY 1.361702 (-13400 4375);
PAINT ORANGE (-13400 4375);
DISPLAY INVISIBLE (-13400 4375);
FORCEPROP 1 LAST OFFPAGE TRUE
J 0
(-12525 4175);
DISPLAY 1.170213 (-12525 4175);
PAINT GREEN (-12525 4175);
DISPLAY INVISIBLE (-12525 4175);
FORCEPROP 1 LAST COMMENT_BODY TRUE
J 0
(-12725 4200);
DISPLAY 1.170213 (-12725 4200);
PAINT GREEN (-12725 4200);
DISPLAY INVISIBLE (-12725 4200);
FORCEADD OFFPAGE..1
(-12850 4350);
FORCEPROP 2 LAST $XR0 236 
J 0
(-13132 4350);
DISPLAY 0.638298 (-13132 4350);
PAINT MONO (-13132 4350);
FORCEPROP 1 LAST COMMENT_BODY TRUE
J 0
(-12725 4250);
DISPLAY 1.170213 (-12725 4250);
PAINT GREEN (-12725 4250);
DISPLAY INVISIBLE (-12725 4250);
FORCEPROP 1 LAST OFFPAGE TRUE
J 0
(-12525 4225);
DISPLAY 1.170213 (-12525 4225);
PAINT GREEN (-12525 4225);
DISPLAY INVISIBLE (-12525 4225);
FORCEPROP 2 LAST ROOM PVNN_PCH_STBY
J 0
(-13400 4425);
DISPLAY 1.361702 (-13400 4425);
PAINT ORANGE (-13400 4425);
DISPLAY INVISIBLE (-13400 4425);
FORCEPROP 2 LAST PATH I186
J 0
(-13100 4400);
DISPLAY 1.021277 (-13100 4400);
PAINT ORANGE (-13100 4400);
DISPLAY INVISIBLE (-13100 4400);
FORCEPROP 2 LAST CDS_LIB mstr_standard
J 0
(-12850 4350);
PAINT ORANGE (-12850 4350);
DISPLAY INVISIBLE (-12850 4350);
FORCEADD OFFPAGE..1
(-12850 4150);
FORCEPROP 2 LAST $XR0 237 
J 0
(-13132 4150);
DISPLAY 0.638298 (-13132 4150);
PAINT MONO (-13132 4150);
FORCEPROP 1 LAST COMMENT_BODY TRUE
J 0
(-12725 4050);
DISPLAY 1.170213 (-12725 4050);
PAINT GREEN (-12725 4050);
DISPLAY INVISIBLE (-12725 4050);
FORCEPROP 1 LAST OFFPAGE TRUE
J 0
(-12525 4025);
DISPLAY 1.170213 (-12525 4025);
PAINT GREEN (-12525 4025);
DISPLAY INVISIBLE (-12525 4025);
FORCEPROP 2 LAST ROOM PVNN_PCH_STBY
J 0
(-13400 4225);
DISPLAY 1.361702 (-13400 4225);
PAINT ORANGE (-13400 4225);
DISPLAY INVISIBLE (-13400 4225);
FORCEPROP 2 LAST CDS_LIB mstr_standard
J 0
(-12850 4150);
PAINT ORANGE (-12850 4150);
DISPLAY INVISIBLE (-12850 4150);
FORCEPROP 2 LAST PATH I187
J 0
(-12800 4225);
DISPLAY 1.021277 (-12800 4225);
PAINT ORANGE (-12800 4225);
DISPLAY INVISIBLE (-12800 4225);
FORCEADD OFFPAGE..1
(-12850 4200);
FORCEPROP 2 LAST $XR0 236 
J 0
(-13132 4200);
DISPLAY 0.638298 (-13132 4200);
PAINT MONO (-13132 4200);
FORCEPROP 1 LAST COMMENT_BODY TRUE
J 0
(-12725 4100);
DISPLAY 1.170213 (-12725 4100);
PAINT GREEN (-12725 4100);
DISPLAY INVISIBLE (-12725 4100);
FORCEPROP 1 LAST OFFPAGE TRUE
J 0
(-12525 4075);
DISPLAY 1.170213 (-12525 4075);
PAINT GREEN (-12525 4075);
DISPLAY INVISIBLE (-12525 4075);
FORCEPROP 2 LAST ROOM PVNN_PCH_STBY
J 0
(-13400 4275);
DISPLAY 1.361702 (-13400 4275);
PAINT ORANGE (-13400 4275);
DISPLAY INVISIBLE (-13400 4275);
FORCEPROP 2 LAST PATH I188
J 0
(-13100 4250);
DISPLAY 1.021277 (-13100 4250);
PAINT ORANGE (-13100 4250);
DISPLAY INVISIBLE (-13100 4250);
FORCEPROP 2 LAST CDS_LIB mstr_standard
J 0
(-12850 4200);
PAINT ORANGE (-12850 4200);
DISPLAY INVISIBLE (-12850 4200);
FORCEADD OFFPAGE..1
(-12850 4050);
FORCEPROP 2 LAST $XR0 235 
J 0
(-13132 4050);
DISPLAY 0.638298 (-13132 4050);
PAINT MONO (-13132 4050);
FORCEPROP 2 LAST PATH I189
J 0
(-13100 4100);
DISPLAY 1.021277 (-13100 4100);
PAINT ORANGE (-13100 4100);
DISPLAY INVISIBLE (-13100 4100);
FORCEPROP 2 LAST ROOM PVNN_PCH_STBY
J 0
(-13400 4125);
DISPLAY 1.361702 (-13400 4125);
PAINT ORANGE (-13400 4125);
DISPLAY INVISIBLE (-13400 4125);
FORCEPROP 2 LAST CDS_LIB mstr_standard
J 0
(-12850 4050);
PAINT ORANGE (-12850 4050);
DISPLAY INVISIBLE (-12850 4050);
FORCEPROP 1 LAST OFFPAGE TRUE
J 0
(-12525 3925);
DISPLAY 1.170213 (-12525 3925);
PAINT GREEN (-12525 3925);
DISPLAY INVISIBLE (-12525 3925);
FORCEPROP 1 LAST COMMENT_BODY TRUE
J 0
(-12725 3950);
DISPLAY 1.170213 (-12725 3950);
PAINT GREEN (-12725 3950);
DISPLAY INVISIBLE (-12725 3950);
FORCEADD OFFPAGE..2
R 2
(-12850 3900);
FORCEPROP 2 LAST $XR0 235 
J 0
(-13105 3900);
DISPLAY 0.638298 (-13105 3900);
PAINT MONO (-13105 3900);
FORCEPROP 2 LAST CDS_LIB mstr_standard
J 0
(-12850 3900);
PAINT ORANGE (-12850 3900);
DISPLAY INVISIBLE (-12850 3900);
FORCEPROP 2 LAST ROOM PVNN_PCH_STBY
J 0
(-13400 3975);
DISPLAY 1.361702 (-13400 3975);
PAINT ORANGE (-13400 3975);
DISPLAY INVISIBLE (-13400 3975);
FORCEPROP 2 LAST PATH I191
J 0
(-13125 3950);
DISPLAY 1.021277 (-13125 3950);
PAINT ORANGE (-13125 3950);
DISPLAY INVISIBLE (-13125 3950);
FORCEPROP 1 LAST OFFPAGE TRUE
J 2
(-13175 3775);
DISPLAY 1.170213 (-13175 3775);
PAINT GREEN (-13175 3775);
DISPLAY INVISIBLE (-13175 3775);
FORCEPROP 1 LAST COMMENT_BODY TRUE
J 2
(-12805 3805);
DISPLAY 1.170213 (-12805 3805);
PAINT GREEN (-12805 3805);
DISPLAY INVISIBLE (-12805 3805);
FORCEADD OFFPAGE..2
R 2
(-12575 3300);
FORCEPROP 1 LAST COMMENT_BODY TRUE
J 2
(-12530 3205);
DISPLAY 1.170213 (-12530 3205);
PAINT GREEN (-12530 3205);
DISPLAY INVISIBLE (-12530 3205);
FORCEPROP 1 LAST OFFPAGE TRUE
J 2
(-12900 3175);
DISPLAY 1.170213 (-12900 3175);
PAINT GREEN (-12900 3175);
DISPLAY INVISIBLE (-12900 3175);
FORCEPROP 2 LAST ROOM PVNN_PCH_STBY
J 0
(-13125 3375);
DISPLAY 1.361702 (-13125 3375);
PAINT ORANGE (-13125 3375);
DISPLAY INVISIBLE (-13125 3375);
FORCEPROP 2 LAST PATH I194
J 0
(-12850 3350);
DISPLAY 1.021277 (-12850 3350);
PAINT ORANGE (-12850 3350);
DISPLAY INVISIBLE (-12850 3350);
FORCEPROP 2 LAST CDS_LIB mstr_standard
J 0
(-12575 3300);
PAINT ORANGE (-12575 3300);
DISPLAY INVISIBLE (-12575 3300);
FORCEPROP 2 LAST $XR11 226 
J 0
(-13004 3300);
DISPLAY 0.638298 (-13004 3300);
PAINT MONO (-13004 3300);
DISPLAY INVISIBLE (-13004 3300);
FORCEPROP 2 LAST $XR10 223 
J 0
(-13004 3300);
DISPLAY 0.638298 (-13004 3300);
PAINT MONO (-13004 3300);
DISPLAY INVISIBLE (-13004 3300);
FORCEPROP 2 LAST $XR9 218 
J 0
(-13004 3300);
DISPLAY 0.638298 (-13004 3300);
PAINT MONO (-13004 3300);
DISPLAY INVISIBLE (-13004 3300);
FORCEPROP 2 LAST $XR8 215 
J 0
(-13004 3300);
DISPLAY 0.638298 (-13004 3300);
PAINT MONO (-13004 3300);
DISPLAY INVISIBLE (-13004 3300);
FORCEPROP 2 LAST $XR7 206 
J 0
(-13004 3300);
DISPLAY 0.638298 (-13004 3300);
PAINT MONO (-13004 3300);
DISPLAY INVISIBLE (-13004 3300);
FORCEPROP 2 LAST $XR6 201 
J 0
(-13004 3300);
DISPLAY 0.638298 (-13004 3300);
PAINT MONO (-13004 3300);
DISPLAY INVISIBLE (-13004 3300);
FORCEPROP 2 LAST $XR5 194 
J 0
(-13004 3300);
DISPLAY 0.638298 (-13004 3300);
PAINT MONO (-13004 3300);
DISPLAY INVISIBLE (-13004 3300);
FORCEPROP 2 LAST $XR4 193 
J 0
(-13004 3300);
DISPLAY 0.638298 (-13004 3300);
PAINT MONO (-13004 3300);
DISPLAY INVISIBLE (-13004 3300);
FORCEPROP 2 LAST $XR3 213 
J 0
(-13004 3300);
DISPLAY 0.638298 (-13004 3300);
PAINT MONO (-13004 3300);
DISPLAY INVISIBLE (-13004 3300);
FORCEPROP 2 LAST $XR2 211 
J 0
(-13004 3300);
DISPLAY 0.638298 (-13004 3300);
PAINT MONO (-13004 3300);
DISPLAY INVISIBLE (-13004 3300);
FORCEPROP 2 LAST $XR1 159 
J 0
(-13004 3300);
DISPLAY 0.638298 (-13004 3300);
PAINT MONO (-13004 3300);
DISPLAY INVISIBLE (-13004 3300);
FORCEPROP 2 LAST $XR0 138 
J 0
(-13004 3300);
DISPLAY 0.638298 (-13004 3300);
PAINT MONO (-13004 3300);
DISPLAY INVISIBLE (-13004 3300);
FORCEADD OFFPAGE..3
R 2
(-12575 3350);
FORCEPROP 2 LAST $XR11 226 
J 0
(-13245 3314);
DISPLAY 0.638298 (-13245 3314);
PAINT MONO (-13245 3314);
FORCEPROP 2 LAST $XR10 223 
J 0
(-13125 3314);
DISPLAY 0.638298 (-13125 3314);
PAINT MONO (-13125 3314);
FORCEPROP 2 LAST $XR9 218 
J 0
(-13005 3314);
DISPLAY 0.638298 (-13005 3314);
PAINT MONO (-13005 3314);
FORCEPROP 2 LAST $XR8 215 
J 0
(-12885 3314);
DISPLAY 0.638298 (-12885 3314);
PAINT MONO (-12885 3314);
FORCEPROP 2 LAST $XR7 213 
J 0
(-13725 3350);
DISPLAY 0.638298 (-13725 3350);
PAINT MONO (-13725 3350);
FORCEPROP 2 LAST $XR6 211 
J 0
(-13605 3350);
DISPLAY 0.638298 (-13605 3350);
PAINT MONO (-13605 3350);
FORCEPROP 2 LAST $XR5 206 
J 0
(-13485 3350);
DISPLAY 0.638298 (-13485 3350);
PAINT MONO (-13485 3350);
FORCEPROP 2 LAST $XR4 201 
J 0
(-13365 3350);
DISPLAY 0.638298 (-13365 3350);
PAINT MONO (-13365 3350);
FORCEPROP 2 LAST $XR3 194 
J 0
(-13245 3350);
DISPLAY 0.638298 (-13245 3350);
PAINT MONO (-13245 3350);
FORCEPROP 2 LAST $XR2 193 
J 0
(-13125 3350);
DISPLAY 0.638298 (-13125 3350);
PAINT MONO (-13125 3350);
FORCEPROP 2 LAST $XR1 159 
J 0
(-13005 3350);
DISPLAY 0.638298 (-13005 3350);
PAINT MONO (-13005 3350);
FORCEPROP 2 LAST $XR0 138 
J 0
(-12885 3350);
DISPLAY 0.638298 (-12885 3350);
PAINT MONO (-12885 3350);
FORCEPROP 1 LAST COMMENT_BODY TRUE
J 2
(-12525 3250);
DISPLAY 0.872340 (-12525 3250);
PAINT GREEN (-12525 3250);
DISPLAY INVISIBLE (-12525 3250);
FORCEPROP 1 LAST OFFPAGE TRUE
J 2
(-12900 3225);
DISPLAY 0.872340 (-12900 3225);
PAINT GREEN (-12900 3225);
DISPLAY INVISIBLE (-12900 3225);
FORCEPROP 2 LAST ROOM PVNN_PCH_STBY
J 0
(-13125 3425);
DISPLAY 1.361702 (-13125 3425);
PAINT ORANGE (-13125 3425);
DISPLAY INVISIBLE (-13125 3425);
FORCEPROP 2 LAST PATH I195
J 0
(-12850 3425);
DISPLAY 1.021277 (-12850 3425);
PAINT ORANGE (-12850 3425);
DISPLAY INVISIBLE (-12850 3425);
FORCEPROP 2 LAST CDS_LIB mstr_standard
J 0
(-12575 3350);
PAINT ORANGE (-12575 3350);
DISPLAY INVISIBLE (-12575 3350);
FORCEADD OFFPAGE..2
(-7125 3950);
FORCEPROP 2 LAST $XR0 236 
J 0
(-6936 3950);
DISPLAY 0.638298 (-6936 3950);
PAINT MONO (-6936 3950);
FORCEPROP 1 LAST COMMENT_BODY TRUE
J 0
(-7170 3855);
DISPLAY 1.170213 (-7170 3855);
PAINT GREEN (-7170 3855);
DISPLAY INVISIBLE (-7170 3855);
FORCEPROP 1 LAST OFFPAGE TRUE
J 0
(-6800 3825);
DISPLAY 1.170213 (-6800 3825);
PAINT GREEN (-6800 3825);
DISPLAY INVISIBLE (-6800 3825);
FORCEPROP 2 LAST ROOM PVNN_PCH_STBY
J 0
(-7550 4025);
DISPLAY 1.361702 (-7550 4025);
PAINT ORANGE (-7550 4025);
DISPLAY INVISIBLE (-7550 4025);
FORCEPROP 2 LAST CDS_LIB mstr_standard
J 0
(-7125 3950);
PAINT ORANGE (-7125 3950);
DISPLAY INVISIBLE (-7125 3950);
FORCEPROP 2 LAST PATH I198
J 0
(-6950 4025);
DISPLAY 1.021277 (-6950 4025);
PAINT ORANGE (-6950 4025);
DISPLAY INVISIBLE (-6950 4025);
FORCEADD OFFPAGE..1
(-13150 3100);
FORCEPROP 2 LAST $XR0 236 
J 0
(-13402 3100);
DISPLAY 0.638298 (-13402 3100);
PAINT MONO (-13402 3100);
FORCEPROP 1 LAST COMMENT_BODY TRUE
J 0
(-13025 3000);
DISPLAY 1.170213 (-13025 3000);
PAINT GREEN (-13025 3000);
DISPLAY INVISIBLE (-13025 3000);
FORCEPROP 1 LAST OFFPAGE TRUE
J 0
(-12825 2975);
DISPLAY 1.170213 (-12825 2975);
PAINT GREEN (-12825 2975);
DISPLAY INVISIBLE (-12825 2975);
FORCEPROP 2 LAST ROOM PVNN_PCH_STBY
J 0
(-13700 3175);
DISPLAY 1.361702 (-13700 3175);
PAINT ORANGE (-13700 3175);
DISPLAY INVISIBLE (-13700 3175);
FORCEPROP 2 LAST CDS_LIB mstr_standard
J 0
(-13150 3100);
PAINT ORANGE (-13150 3100);
DISPLAY INVISIBLE (-13150 3100);
FORCEPROP 2 LAST PATH I199
J 0
(-13100 3175);
DISPLAY 1.021277 (-13100 3175);
PAINT ORANGE (-13100 3175);
DISPLAY INVISIBLE (-13100 3175);
FORCEADD OFFPAGE..1
(-13150 3050);
FORCEPROP 2 LAST $XR0 236 
J 0
(-13402 3050);
DISPLAY 0.638298 (-13402 3050);
PAINT MONO (-13402 3050);
FORCEPROP 1 LAST COMMENT_BODY TRUE
J 0
(-13025 2950);
DISPLAY 1.170213 (-13025 2950);
PAINT GREEN (-13025 2950);
DISPLAY INVISIBLE (-13025 2950);
FORCEPROP 1 LAST OFFPAGE TRUE
J 0
(-12825 2925);
DISPLAY 1.170213 (-12825 2925);
PAINT GREEN (-12825 2925);
DISPLAY INVISIBLE (-12825 2925);
FORCEPROP 2 LAST CDS_LIB mstr_standard
J 0
(-13150 3050);
PAINT ORANGE (-13150 3050);
DISPLAY INVISIBLE (-13150 3050);
FORCEPROP 2 LAST ROOM PVNN_PCH_STBY
J 0
(-13700 3125);
DISPLAY 1.361702 (-13700 3125);
PAINT ORANGE (-13700 3125);
DISPLAY INVISIBLE (-13700 3125);
FORCEPROP 2 LAST PATH I200
J 0
(-13100 3125);
DISPLAY 1.021277 (-13100 3125);
PAINT ORANGE (-13100 3125);
DISPLAY INVISIBLE (-13100 3125);
FORCEADD CAP..1
(-12375 2600);
FORCEPROP 1 LASTPIN (-12375 2500) $PN 2
J 0
(-12365 2480);
DISPLAY 0.617021 (-12365 2480);
PAINT ORANGE (-12365 2480);
FORCEPROP 1 LAST TOLERANCE 10%
J 0
(-12150 2650);
DISPLAY 0.617021 (-12150 2650);
PAINT SKYBLUE (-12150 2650);
FORCEPROP 1 LAST MATERIAL X7R
J 0
(-12200 2600);
DISPLAY 0.617021 (-12200 2600);
PAINT SKYBLUE (-12200 2600);
FORCEPROP 1 LAST VOLTAGE 50V
J 0
(-12325 2600);
DISPLAY 0.617021 (-12325 2600);
PAINT SKYBLUE (-12325 2600);
FORCEPROP 1 LAST PACK_TYPE 0402LF
J 0
(-12325 2500);
DISPLAY 0.617021 (-12325 2500);
PAINT SKYBLUE (-12325 2500);
FORCEPROP 1 LAST VALUE 220PF
J 0
(-12325 2650);
DISPLAY 0.617021 (-12325 2650);
PAINT SKYBLUE (-12325 2650);
FORCEPROP 1 LASTPIN (-12375 2700) $PN 1
J 0
(-12365 2680);
DISPLAY 0.617021 (-12365 2680);
PAINT ORANGE (-12365 2680);
FORCEPROP 1 LAST LOCATION C8A2
J 0
(-12325 2700);
DISPLAY 0.617021 (-12325 2700);
PAINT AQUA (-12325 2700);
FORCEPROP 1 LAST PART_NUMBER A36096-050
J 0
(-12325 2550);
DISPLAY 0.617021 (-12325 2550);
PAINT BLUE (-12325 2550);
FORCEPROP 2 LAST CDS_LIB mstr_discrete
J 0
(-12375 2600);
PAINT ORANGE (-12375 2600);
DISPLAY INVISIBLE (-12375 2600);
FORCEPROP 2 LAST CDS_LOCATION C8A2
J 0
(-12325 2700);
DISPLAY 0.617021 (-12325 2700);
PAINT AQUA (-12325 2700);
DISPLAY INVISIBLE (-12325 2700);
FORCEPROP 1 LAST PATH I209
J 0
(-12325 2750);
DISPLAY 0.978723 (-12325 2750);
PAINT WHITE (-12325 2750);
DISPLAY INVISIBLE (-12325 2750);
FORCEPROP 2 LAST ROOM PVNN_PCH_STBY
J 0
(-12325 2750);
DISPLAY 1.361702 (-12325 2750);
PAINT ORANGE (-12325 2750);
DISPLAY INVISIBLE (-12325 2750);
FORCEPROP 2 LAST SEC_TYPE 0402LF
J 0
(-12325 2825);
DISPLAY 1.021277 (-12325 2825);
PAINT ORANGE (-12325 2825);
DISPLAY INVISIBLE (-12325 2825);
FORCEPROP 2 LAST SEC 1
J 0
(-12325 2825);
DISPLAY 0.680851 (-12325 2825);
PAINT MONO (-12325 2825);
DISPLAY INVISIBLE (-12325 2825);
FORCEPROP 0 LAST NO_XNET_CONNECTION 1
J 0
(-12475 2550);
PAINT MONO (-12475 2550);
DISPLAY INVISIBLE (-12475 2550);
FORCEADD RES..1
(-12675 2750);
FORCEPROP 1 LAST MATERIAL CHIP
J 0
(-12650 2600);
DISPLAY 0.617021 (-12650 2600);
PAINT SKYBLUE (-12650 2600);
FORCEPROP 1 LAST PACK_TYPE 0402
J 0
(-12650 2650);
DISPLAY 0.617021 (-12650 2650);
PAINT SKYBLUE (-12650 2650);
FORCEPROP 1 LAST PART_NUMBER G21796-066
J 0
(-12825 2700);
DISPLAY 0.617021 (-12825 2700);
PAINT BLUE (-12825 2700);
FORCEPROP 1 LASTPIN (-12775 2750) $PN 1
J 0
(-12763 2762);
DISPLAY 0.617021 (-12763 2762);
PAINT ORANGE (-12763 2762);
FORCEPROP 1 LAST WATTAGE 1/16W
J 2
(-12675 2600);
DISPLAY 0.617021 (-12675 2600);
PAINT SKYBLUE (-12675 2600);
FORCEPROP 1 LAST VALUE 10.0
J 2
(-12775 2650);
DISPLAY 0.617021 (-12775 2650);
PAINT SKYBLUE (-12775 2650);
FORCEPROP 1 LAST TOLERANCE 1%
J 0
(-12750 2650);
DISPLAY 0.617021 (-12750 2650);
PAINT SKYBLUE (-12750 2650);
FORCEPROP 1 LASTPIN (-12575 2750) $PN 2
J 0
(-12613 2762);
DISPLAY 0.617021 (-12613 2762);
PAINT ORANGE (-12613 2762);
FORCEPROP 1 LAST LOCATION R8A1
J 0
(-12725 2800);
DISPLAY 0.617021 (-12725 2800);
PAINT AQUA (-12725 2800);
FORCEPROP 2 LAST ROOM PVNN_PCH_STBY
J 0
(-12600 2850);
DISPLAY 1.361702 (-12600 2850);
PAINT ORANGE (-12600 2850);
DISPLAY INVISIBLE (-12600 2850);
FORCEPROP 2 LAST SEC_TYPE 0402
J 0
(-12725 2975);
DISPLAY 1.021277 (-12725 2975);
PAINT ORANGE (-12725 2975);
DISPLAY INVISIBLE (-12725 2975);
FORCEPROP 2 LAST SEC 1
J 0
(-12725 2975);
DISPLAY 0.680851 (-12725 2975);
PAINT MONO (-12725 2975);
DISPLAY INVISIBLE (-12725 2975);
FORCEPROP 1 LAST PATH I210
J 0
(-12725 2900);
DISPLAY 0.978723 (-12725 2900);
PAINT WHITE (-12725 2900);
DISPLAY INVISIBLE (-12725 2900);
FORCEPROP 2 LAST CDS_LOCATION R8A1
J 0
(-12725 2800);
DISPLAY 0.617021 (-12725 2800);
PAINT AQUA (-12725 2800);
DISPLAY INVISIBLE (-12725 2800);
FORCEPROP 2 LAST CDS_LIB mstr_discrete
J 0
(-12675 2750);
PAINT ORANGE (-12675 2750);
DISPLAY INVISIBLE (-12675 2750);
FORCEPROP 0 LAST NO_XNET_CONNECTION 1
J 0
(-12925 2650);
PAINT MONO (-12925 2650);
DISPLAY INVISIBLE (-12925 2650);
FORCEADD OFFPAGE..1
(-13450 2750);
FORCEPROP 2 LAST $XR0 236 
J 0
(-13732 2750);
DISPLAY 0.638298 (-13732 2750);
PAINT MONO (-13732 2750);
FORCEPROP 1 LAST COMMENT_BODY TRUE
J 0
(-13325 2650);
DISPLAY 1.170213 (-13325 2650);
PAINT GREEN (-13325 2650);
DISPLAY INVISIBLE (-13325 2650);
FORCEPROP 1 LAST OFFPAGE TRUE
J 0
(-13125 2625);
DISPLAY 1.170213 (-13125 2625);
PAINT GREEN (-13125 2625);
DISPLAY INVISIBLE (-13125 2625);
FORCEPROP 2 LAST ROOM PVNN_PCH_STBY
J 0
(-14000 2825);
DISPLAY 1.361702 (-14000 2825);
PAINT ORANGE (-14000 2825);
DISPLAY INVISIBLE (-14000 2825);
FORCEPROP 2 LAST CDS_LIB mstr_standard
J 0
(-13450 2750);
PAINT ORANGE (-13450 2750);
DISPLAY INVISIBLE (-13450 2750);
FORCEPROP 2 LAST PATH I211
J 0
(-13400 2825);
DISPLAY 1.021277 (-13400 2825);
PAINT ORANGE (-13400 2825);
DISPLAY INVISIBLE (-13400 2825);
FORCEADD OFFPAGE..1
(-13450 2475);
FORCEPROP 2 LAST $XR0 236 
J 0
(-13732 2475);
DISPLAY 0.638298 (-13732 2475);
PAINT MONO (-13732 2475);
FORCEPROP 2 LAST PATH I212
J 0
(-13400 2550);
DISPLAY 1.021277 (-13400 2550);
PAINT ORANGE (-13400 2550);
DISPLAY INVISIBLE (-13400 2550);
FORCEPROP 2 LAST CDS_LIB mstr_standard
J 0
(-13450 2475);
PAINT ORANGE (-13450 2475);
DISPLAY INVISIBLE (-13450 2475);
FORCEPROP 2 LAST ROOM PVNN_PCH_STBY
J 0
(-14000 2550);
DISPLAY 1.361702 (-14000 2550);
PAINT ORANGE (-14000 2550);
DISPLAY INVISIBLE (-14000 2550);
FORCEPROP 1 LAST OFFPAGE TRUE
J 0
(-13125 2350);
DISPLAY 1.170213 (-13125 2350);
PAINT GREEN (-13125 2350);
DISPLAY INVISIBLE (-13125 2350);
FORCEPROP 1 LAST COMMENT_BODY TRUE
J 0
(-13325 2375);
DISPLAY 1.170213 (-13325 2375);
PAINT GREEN (-13325 2375);
DISPLAY INVISIBLE (-13325 2375);
FORCEADD OFFPAGE..1
(-13150 3200);
FORCEPROP 2 LAST $XR0 236 
J 0
(-13402 3200);
DISPLAY 0.638298 (-13402 3200);
PAINT MONO (-13402 3200);
FORCEPROP 1 LAST COMMENT_BODY TRUE
J 0
(-13025 3100);
DISPLAY 1.170213 (-13025 3100);
PAINT GREEN (-13025 3100);
DISPLAY INVISIBLE (-13025 3100);
FORCEPROP 1 LAST OFFPAGE TRUE
J 0
(-12825 3075);
DISPLAY 1.170213 (-12825 3075);
PAINT GREEN (-12825 3075);
DISPLAY INVISIBLE (-12825 3075);
FORCEPROP 2 LAST ROOM PVNN_PCH_STBY
J 0
(-13700 3275);
DISPLAY 1.361702 (-13700 3275);
PAINT ORANGE (-13700 3275);
DISPLAY INVISIBLE (-13700 3275);
FORCEPROP 2 LAST CDS_LIB mstr_standard
J 0
(-13150 3200);
PAINT ORANGE (-13150 3200);
DISPLAY INVISIBLE (-13150 3200);
FORCEPROP 2 LAST PATH I215
J 0
(-13100 3275);
DISPLAY 1.021277 (-13100 3275);
PAINT ORANGE (-13100 3275);
DISPLAY INVISIBLE (-13100 3275);
FORCEADD RES..2
(-8075 4950);
FORCEPROP 1 LAST PACK_TYPE 0402
J 0
(-8035 4775);
DISPLAY 0.617021 (-8035 4775);
PAINT SKYBLUE (-8035 4775);
FORCEPROP 1 LAST PART_NUMBER G21796-026
J 0
(-8035 4825);
DISPLAY 0.617021 (-8035 4825);
PAINT BLUE (-8035 4825);
FORCEPROP 1 LAST TOLERANCE 1%
J 0
(-8030 4975);
DISPLAY 0.617021 (-8030 4975);
PAINT SKYBLUE (-8030 4975);
FORCEPROP 1 LASTPIN (-8075 5050) $PN 1
J 0
(-8070 5012);
DISPLAY 0.787234 (-8070 5012);
PAINT ORANGE (-8070 5012);
FORCEPROP 1 LAST WATTAGE 1/16W
J 0
(-8035 4925);
DISPLAY 0.617021 (-8035 4925);
PAINT SKYBLUE (-8035 4925);
FORCEPROP 1 LAST VALUE 1.00K
J 0
(-8030 5025);
DISPLAY 0.617021 (-8030 5025);
PAINT SKYBLUE (-8030 5025);
FORCEPROP 1 LAST LOCATION R8A5
J 0
(-8030 5075);
DISPLAY 0.617021 (-8030 5075);
PAINT AQUA (-8030 5075);
FORCEPROP 1 LAST MATERIAL CHIP
J 0
(-8035 4875);
DISPLAY 0.617021 (-8035 4875);
PAINT SKYBLUE (-8035 4875);
FORCEPROP 1 LASTPIN (-8075 4850) $PN 2
J 0
(-8070 4860);
DISPLAY 0.787234 (-8070 4860);
PAINT ORANGE (-8070 4860);
FORCEPROP 2 LAST SEC 1
J 0
(-8025 5175);
DISPLAY 0.680851 (-8025 5175);
PAINT MONO (-8025 5175);
DISPLAY INVISIBLE (-8025 5175);
FORCEPROP 2 LAST SEC_TYPE 0402
J 0
(-8025 5175);
DISPLAY 1.021277 (-8025 5175);
PAINT ORANGE (-8025 5175);
DISPLAY INVISIBLE (-8025 5175);
FORCEPROP 2 LAST CDS_LOCATION R8A5
J 0
(-8030 5075);
DISPLAY 0.617021 (-8030 5075);
PAINT AQUA (-8030 5075);
DISPLAY INVISIBLE (-8030 5075);
FORCEPROP 1 LAST PATH I216
J 0
(-8025 5125);
DISPLAY 0.978723 (-8025 5125);
PAINT WHITE (-8025 5125);
DISPLAY INVISIBLE (-8025 5125);
FORCEPROP 2 LAST CDS_LIB mstr_discrete
J 0
(-8075 4950);
PAINT ORANGE (-8075 4950);
DISPLAY INVISIBLE (-8075 4950);
FORCEADD RES..2
(-10450 2150);
FORCEPROP 1 LAST VALUE 2.67K
J 0
(-10405 2225);
DISPLAY 0.617021 (-10405 2225);
PAINT SKYBLUE (-10405 2225);
FORCEPROP 1 LAST MATERIAL CHIP
J 0
(-10410 2075);
DISPLAY 0.617021 (-10410 2075);
PAINT SKYBLUE (-10410 2075);
FORCEPROP 1 LASTPIN (-10450 2050) $PN 2
J 0
(-10445 2060);
DISPLAY 0.787234 (-10445 2060);
PAINT ORANGE (-10445 2060);
FORCEPROP 1 LAST LOCATION R8A2
J 0
(-10405 2275);
DISPLAY 0.617021 (-10405 2275);
PAINT AQUA (-10405 2275);
FORCEPROP 1 LAST PACK_TYPE 0402
J 0
(-10410 1975);
DISPLAY 0.617021 (-10410 1975);
PAINT SKYBLUE (-10410 1975);
FORCEPROP 1 LAST PART_NUMBER G21796-180
J 0
(-10410 2025);
DISPLAY 0.617021 (-10410 2025);
PAINT BLUE (-10410 2025);
FORCEPROP 1 LAST WATTAGE 1/16W
J 0
(-10410 2125);
DISPLAY 0.617021 (-10410 2125);
PAINT SKYBLUE (-10410 2125);
FORCEPROP 1 LASTPIN (-10450 2250) $PN 1
J 0
(-10445 2212);
DISPLAY 0.787234 (-10445 2212);
PAINT ORANGE (-10445 2212);
FORCEPROP 1 LAST TOLERANCE 1%
J 0
(-10405 2175);
DISPLAY 0.617021 (-10405 2175);
PAINT SKYBLUE (-10405 2175);
FORCEPROP 2 LAST SEC 1
J 0
(-10400 2375);
DISPLAY 0.680851 (-10400 2375);
PAINT MONO (-10400 2375);
DISPLAY INVISIBLE (-10400 2375);
FORCEPROP 2 LAST SEC_TYPE 0402
J 0
(-10400 2375);
DISPLAY 1.021277 (-10400 2375);
PAINT ORANGE (-10400 2375);
DISPLAY INVISIBLE (-10400 2375);
FORCEPROP 1 LAST PATH I217
J 0
(-10400 2325);
DISPLAY 0.978723 (-10400 2325);
PAINT WHITE (-10400 2325);
DISPLAY INVISIBLE (-10400 2325);
FORCEPROP 2 LAST CDS_LOCATION R8A2
J 0
(-10405 2275);
DISPLAY 0.617021 (-10405 2275);
PAINT AQUA (-10405 2275);
DISPLAY INVISIBLE (-10405 2275);
FORCEPROP 2 LAST CDS_LIB mstr_discrete
J 0
(-10450 2150);
PAINT ORANGE (-10450 2150);
DISPLAY INVISIBLE (-10450 2150);
FORCEADD CAP..1
(-8000 4325);
FORCEPROP 1 LAST LOCATION C8A9
J 0
(-7950 4425);
DISPLAY 0.617021 (-7950 4425);
PAINT AQUA (-7950 4425);
FORCEPROP 1 LASTPIN (-8000 4225) $PN 2
J 0
(-7990 4205);
DISPLAY 0.617021 (-7990 4205);
PAINT ORANGE (-7990 4205);
FORCEPROP 1 LAST TOLERANCE 10%
J 0
(-7950 4275);
DISPLAY 0.617021 (-7950 4275);
PAINT SKYBLUE (-7950 4275);
FORCEPROP 1 LAST VOLTAGE 50V
J 0
(-7950 4325);
DISPLAY 0.617021 (-7950 4325);
PAINT SKYBLUE (-7950 4325);
FORCEPROP 1 LAST VALUE 1000PF
J 0
(-7950 4375);
DISPLAY 0.617021 (-7950 4375);
PAINT SKYBLUE (-7950 4375);
FORCEPROP 1 LASTPIN (-8000 4425) $PN 1
J 0
(-7990 4405);
DISPLAY 0.617021 (-7990 4405);
PAINT ORANGE (-7990 4405);
FORCEPROP 1 LAST PACK_TYPE 0402LF
J 0
(-7950 4125);
DISPLAY 0.617021 (-7950 4125);
PAINT SKYBLUE (-7950 4125);
FORCEPROP 1 LAST PART_NUMBER A36096-046
J 0
(-7950 4175);
DISPLAY 0.617021 (-7950 4175);
PAINT BLUE (-7950 4175);
FORCEPROP 1 LAST MATERIAL X7R
J 0
(-7950 4225);
DISPLAY 0.617021 (-7950 4225);
PAINT SKYBLUE (-7950 4225);
FORCEPROP 2 LAST CDS_LIB mstr_discrete
J 0
(-8000 4325);
PAINT MONO (-8000 4325);
DISPLAY INVISIBLE (-8000 4325);
FORCEPROP 2 LAST CDS_LOCATION C8A9
J 0
(-7950 4425);
DISPLAY 0.617021 (-7950 4425);
PAINT AQUA (-7950 4425);
DISPLAY INVISIBLE (-7950 4425);
FORCEPROP 1 LAST PATH I218
J 0
(-7950 4475);
DISPLAY 0.978723 (-7950 4475);
PAINT WHITE (-7950 4475);
DISPLAY INVISIBLE (-7950 4475);
FORCEPROP 0 LAST ROOM PVNN_PCH_STBY
J 0
(-7950 4525);
DISPLAY 1.021277 (-7950 4525);
PAINT ORANGE (-7950 4525);
DISPLAY INVISIBLE (-7950 4525);
FORCEPROP 2 LAST SEC 1
J 0
(-7950 4525);
DISPLAY 0.680851 (-7950 4525);
PAINT MONO (-7950 4525);
DISPLAY INVISIBLE (-7950 4525);
FORCEPROP 2 LAST SEC_TYPE 0402LF
J 0
(-7950 4525);
DISPLAY 1.021277 (-7950 4525);
PAINT ORANGE (-7950 4525);
DISPLAY INVISIBLE (-7950 4525);
FORCEADD GND..1
(-8000 4075);
FORCEPROP 3 LASTPIN (-8000 4125) SIG_NAME GND\g
J 0
(-7990 4135);
DISPLAY 0.659574 (-7990 4135);
PAINT MONO (-7990 4135);
DISPLAY INVISIBLE (-7990 4135);
FORCEPROP 1 LAST HDL_POWER GND
J 0
(-8000 4225);
DISPLAY 1.170213 (-8000 4225);
PAINT GREEN (-8000 4225);
DISPLAY INVISIBLE (-8000 4225);
FORCEPROP 1 LAST BODY_TYPE PLUMBING
J 0
(-8045 4032);
DISPLAY 0.340426 (-8045 4032);
PAINT GREEN (-8045 4032);
DISPLAY INVISIBLE (-8045 4032);
FORCEPROP 2 LAST ROOM PVNN_PCH_STBY
J 0
(-8575 4150);
DISPLAY 1.361702 (-8575 4150);
PAINT ORANGE (-8575 4150);
DISPLAY INVISIBLE (-8575 4150);
FORCEPROP 1 LAST SIZE 1B
J 0
(-7925 4025);
DISPLAY 1.170213 (-7925 4025);
PAINT AQUA (-7925 4025);
DISPLAY INVISIBLE (-7925 4025);
FORCEPROP 1 LAST PATH I219
J 0
(-7925 4075);
DISPLAY 0.872340 (-7925 4075);
PAINT AQUA (-7925 4075);
DISPLAY INVISIBLE (-7925 4075);
FORCEPROP 2 LAST CDS_LIB mstr_symbols
J 0
(-8000 4075);
PAINT MONO (-8000 4075);
DISPLAY INVISIBLE (-8000 4075);
FORCEPROP 1 LAST VOLTAGE 0
J 0
(-8000 4075);
PAINT SKYBLUE (-8000 4075);
DISPLAY INVISIBLE (-8000 4075);
FORCEADD RES..1
(-11800 4150);
FORCEPROP 1 LAST PART_NUMBER G21497-005
J 0
(-11775 4225);
DISPLAY 0.617021 (-11775 4225);
PAINT BLUE (-11775 4225);
FORCEPROP 1 LAST LOCATION R2L17
J 0
(-11925 4225);
DISPLAY 0.617021 (-11925 4225);
PAINT AQUA (-11925 4225);
FORCEPROP 1 LAST PACK_TYPE 0402
J 0
(-11775 4050);
DISPLAY 0.617021 (-11775 4050);
PAINT SKYBLUE (-11775 4050);
FORCEPROP 1 LAST MATERIAL CHIP
J 0
(-11900 4050);
DISPLAY 0.617021 (-11900 4050);
PAINT SKYBLUE (-11900 4050);
FORCEPROP 1 LASTPIN (-11900 4150) $PN 1
J 0
(-11888 4162);
DISPLAY 0.617021 (-11888 4162);
PAINT ORANGE (-11888 4162);
FORCEPROP 1 LAST VALUE 0.0
J 2
(-11875 4100);
DISPLAY 0.617021 (-11875 4100);
PAINT SKYBLUE (-11875 4100);
FORCEPROP 1 LAST TOLERANCE 5%
J 0
(-11850 4100);
DISPLAY 0.617021 (-11850 4100);
PAINT SKYBLUE (-11850 4100);
FORCEPROP 1 LASTPIN (-11700 4150) $PN 2
J 0
(-11738 4162);
DISPLAY 0.617021 (-11738 4162);
PAINT ORANGE (-11738 4162);
FORCEPROP 1 LAST WATTAGE 1/16W
J 2
(-11625 4100);
DISPLAY 0.617021 (-11625 4100);
PAINT SKYBLUE (-11625 4100);
FORCEPROP 2 LAST ROOM PVCCIN_CPU0_VR
J 0
(-11850 4250);
DISPLAY 1.361702 (-11850 4250);
PAINT ORANGE (-11850 4250);
DISPLAY INVISIBLE (-11850 4250);
FORCEPROP 2 LAST CDS_LOCATION R2L17
J 0
(-11850 4200);
DISPLAY 0.617021 (-11850 4200);
PAINT AQUA (-11850 4200);
DISPLAY INVISIBLE (-11850 4200);
FORCEPROP 2 LAST CDS_LIB mstr_discrete
J 0
(-11800 4150);
PAINT ORANGE (-11800 4150);
DISPLAY INVISIBLE (-11800 4150);
FORCEPROP 1 LAST PATH I221
J 0
(-11850 4300);
DISPLAY 0.978723 (-11850 4300);
PAINT WHITE (-11850 4300);
DISPLAY INVISIBLE (-11850 4300);
FORCEPROP 2 LAST SEC 1
J 0
(-11850 4350);
PAINT MONO (-11850 4350);
DISPLAY INVISIBLE (-11850 4350);
FORCEPROP 2 LAST SEC_TYPE 0402
J 0
(-11850 4350);
DISPLAY 1.021277 (-11850 4350);
PAINT ORANGE (-11850 4350);
DISPLAY INVISIBLE (-11850 4350);
FORCEADD RES..2
(-11175 5075);
FORCEPROP 1 LAST WATTAGE 1/16W
J 0
(-11135 5050);
DISPLAY 0.617021 (-11135 5050);
PAINT SKYBLUE (-11135 5050);
FORCEPROP 1 LASTPIN (-11175 5175) $PN 1
J 0
(-11170 5137);
DISPLAY 0.617021 (-11170 5137);
PAINT ORANGE (-11170 5137);
FORCEPROP 1 LAST TOLERANCE 1%
J 0
(-11130 5100);
DISPLAY 0.617021 (-11130 5100);
PAINT SKYBLUE (-11130 5100);
FORCEPROP 1 LAST VALUE 100.0K
J 0
(-11130 5150);
DISPLAY 0.617021 (-11130 5150);
PAINT SKYBLUE (-11130 5150);
FORCEPROP 1 LAST LOCATION R8A7
J 0
(-11130 5200);
DISPLAY 0.617021 (-11130 5200);
PAINT AQUA (-11130 5200);
FORCEPROP 1 LASTPIN (-11175 4975) $PN 2
J 0
(-11170 4985);
DISPLAY 0.617021 (-11170 4985);
PAINT ORANGE (-11170 4985);
FORCEPROP 1 LAST MATERIAL EMPTY
J 0
(-11135 5000);
DISPLAY 0.617021 (-11135 5000);
PAINT RED (-11135 5000);
FORCEPROP 1 LAST PACK_TYPE 0402
J 0
(-11135 4900);
DISPLAY 0.617021 (-11135 4900);
PAINT SKYBLUE (-11135 4900);
FORCEPROP 1 LAST PART_NUMBER G21796-010
J 0
(-11135 4950);
DISPLAY 0.617021 (-11135 4950);
PAINT BLUE (-11135 4950);
FORCEPROP 2 LAST CDS_LIB mstr_discrete
J 0
(-11175 5075);
PAINT ORANGE (-11175 5075);
DISPLAY INVISIBLE (-11175 5075);
FORCEPROP 0 LAST ROOM BMC
J 0
(-11125 5300);
DISPLAY 0.617021 (-11125 5300);
PAINT ORANGE (-11125 5300);
DISPLAY INVISIBLE (-11125 5300);
FORCEPROP 1 LAST PATH I222
J 0
(-11125 5250);
DISPLAY 0.978723 (-11125 5250);
PAINT WHITE (-11125 5250);
DISPLAY INVISIBLE (-11125 5250);
FORCEPROP 2 LAST CDS_LOCATION R8A7
J 0
(-11130 5200);
DISPLAY 0.617021 (-11130 5200);
PAINT AQUA (-11130 5200);
DISPLAY INVISIBLE (-11130 5200);
FORCEPROP 2 LAST SEC 1
J 0
(-11125 5300);
PAINT MONO (-11125 5300);
DISPLAY INVISIBLE (-11125 5300);
FORCEPROP 2 LAST SEC_TYPE 0402
J 0
(-11125 5300);
DISPLAY 1.021277 (-11125 5300);
PAINT ORANGE (-11125 5300);
DISPLAY INVISIBLE (-11125 5300);
FORCEPROP 0 LAST BOM_COST SM_CONTROLLER
J 0
(-11125 5400);
DISPLAY 1.021277 (-11125 5400);
PAINT ORANGE (-11125 5400);
DISPLAY INVISIBLE (-11125 5400);
FORCEADD VCC_CORE..1
(-12325 5750);
FORCEPROP 3 LASTPIN (-12325 5700) SIG_NAME VR_FET_SW_P12V_STBY_PVDDQ_DEF\g
J 0
(-12315 5710);
DISPLAY 0.659574 (-12315 5710);
PAINT MONO (-12315 5710);
DISPLAY INVISIBLE (-12315 5710);
FORCEPROP 1 LAST HDL_POWER VR_FET_SW_P12V_STBY_PVDDQ_DEF
J 1
(-12325 5800);
DISPLAY 0.617021 (-12325 5800);
PAINT GREEN (-12325 5800);
FORCEPROP 2 LAST CDS_LIB mstr_symbols
J 0
(-12325 5750);
PAINT ORANGE (-12325 5750);
DISPLAY INVISIBLE (-12325 5750);
FORCEPROP 1 LAST PATH I228
J 0
(-12275 5775);
DISPLAY 0.872340 (-12275 5775);
PAINT AQUA (-12275 5775);
DISPLAY INVISIBLE (-12275 5775);
FORCEADD PXE1110B..1
(-9725 3750);
FORCEPROP 2 LASTPIN (-10175 3200) $PN 34
J 2
(-10185 3210);
DISPLAY 0.617021 (-10185 3210);
PAINT ORANGE (-10185 3210);
FORCEPROP 2 LASTPIN (-10175 3100) $PN 25
J 2
(-10185 3110);
DISPLAY 0.617021 (-10185 3110);
PAINT ORANGE (-10185 3110);
FORCEPROP 2 LASTPIN (-10175 3050) $PN 26
J 2
(-10185 3060);
DISPLAY 0.617021 (-10185 3060);
PAINT ORANGE (-10185 3060);
FORCEPROP 2 LASTPIN (-10175 3000) $PN 36
J 2
(-10185 3010);
DISPLAY 0.617021 (-10185 3010);
PAINT ORANGE (-10185 3010);
FORCEPROP 2 LASTPIN (-10175 2950) $PN 33
J 2
(-10185 2960);
DISPLAY 0.617021 (-10185 2960);
PAINT ORANGE (-10185 2960);
FORCEPROP 2 LASTPIN (-10175 4200) $PN 35
J 2
(-10185 4210);
DISPLAY 0.617021 (-10185 4210);
PAINT ORANGE (-10185 4210);
FORCEPROP 2 LASTPIN (-10175 4000) $PN 38
J 2
(-10185 4010);
DISPLAY 0.617021 (-10185 4010);
PAINT ORANGE (-10185 4010);
FORCEPROP 2 LASTPIN (-10175 4300) $PN 22
J 2
(-10185 4310);
DISPLAY 0.617021 (-10185 4310);
PAINT ORANGE (-10185 4310);
FORCEPROP 2 LASTPIN (-10175 3900) $PN 40
J 2
(-10185 3910);
DISPLAY 0.617021 (-10185 3910);
PAINT ORANGE (-10185 3910);
FORCEPROP 2 LASTPIN (-9275 4150) $PN 11
J 0
(-9265 4160);
DISPLAY 0.617021 (-9265 4160);
PAINT ORANGE (-9265 4160);
FORCEPROP 2 LASTPIN (-9275 4500) $PN 9
J 0
(-9265 4510);
DISPLAY 0.617021 (-9265 4510);
PAINT ORANGE (-9265 4510);
FORCEPROP 2 LASTPIN (-9275 3200) $PN 41
J 0
(-9265 3210);
DISPLAY 0.617021 (-9265 3210);
PAINT ORANGE (-9265 3210);
FORCEPROP 2 LASTPIN (-9275 3800) $PN 32
J 0
(-9265 3810);
DISPLAY 0.617021 (-9265 3810);
PAINT ORANGE (-9265 3810);
FORCEPROP 2 LASTPIN (-9275 3600) $PN 13
J 0
(-9265 3610);
DISPLAY 0.617021 (-9265 3610);
PAINT ORANGE (-9265 3610);
FORCEPROP 2 LASTPIN (-9275 3050) $PN 23
J 0
(-9265 3060);
DISPLAY 0.617021 (-9265 3060);
PAINT ORANGE (-9265 3060);
FORCEPROP 2 LASTPIN (-9275 3450) $PN 24
J 0
(-9265 3460);
DISPLAY 0.617021 (-9265 3460);
PAINT ORANGE (-9265 3460);
FORCEPROP 2 LASTPIN (-9275 3900) $PN 5
J 0
(-9265 3910);
DISPLAY 0.617021 (-9265 3910);
PAINT ORANGE (-9265 3910);
FORCEPROP 2 LASTPIN (-9275 3400) $PN 4
J 0
(-9265 3410);
DISPLAY 0.617021 (-9265 3410);
PAINT ORANGE (-9265 3410);
FORCEPROP 2 LASTPIN (-9275 3350) $PN 2
J 0
(-9265 3360);
DISPLAY 0.617021 (-9265 3360);
PAINT ORANGE (-9265 3360);
FORCEPROP 2 LASTPIN (-10175 3300) $PN 7
J 2
(-10185 3310);
DISPLAY 0.617021 (-10185 3310);
PAINT ORANGE (-10185 3310);
FORCEPROP 2 LASTPIN (-10175 3450) $PN 30
J 2
(-10185 3460);
DISPLAY 0.617021 (-10185 3460);
PAINT ORANGE (-10185 3460);
FORCEPROP 2 LASTPIN (-9275 3000) $PN 27
J 0
(-9265 3010);
DISPLAY 0.617021 (-9265 3010);
PAINT ORANGE (-9265 3010);
FORCEPROP 2 LASTPIN (-10175 3500) $PN 29
J 2
(-10185 3510);
DISPLAY 0.617021 (-10185 3510);
PAINT ORANGE (-10185 3510);
FORCEPROP 2 LASTPIN (-10175 3550) $PN 20
J 2
(-10185 3560);
DISPLAY 0.617021 (-10185 3560);
PAINT ORANGE (-10185 3560);
FORCEPROP 2 LASTPIN (-10175 4050) $PN 37
J 2
(-10185 4060);
DISPLAY 0.617021 (-10185 4060);
PAINT ORANGE (-10185 4060);
FORCEPROP 2 LASTPIN (-10175 3850) $PN 16
J 2
(-10185 3860);
DISPLAY 0.617021 (-10185 3860);
PAINT ORANGE (-10185 3860);
FORCEPROP 2 LASTPIN (-10175 3700) $PN 8
J 2
(-10185 3710);
DISPLAY 0.617021 (-10185 3710);
PAINT ORANGE (-10185 3710);
FORCEPROP 2 LASTPIN (-9275 3500) $PN 28
J 0
(-9265 3510);
DISPLAY 0.617021 (-9265 3510);
PAINT ORANGE (-9265 3510);
FORCEPROP 2 LASTPIN (-10175 3600) $PN 19
J 2
(-10185 3610);
DISPLAY 0.617021 (-10185 3610);
PAINT ORANGE (-10185 3610);
FORCEPROP 2 LASTPIN (-10175 4450) $PN 15
J 2
(-10185 4460);
DISPLAY 0.617021 (-10185 4460);
PAINT ORANGE (-10185 4460);
FORCEPROP 2 LASTPIN (-10175 4500) $PN 39
J 2
(-10185 4510);
DISPLAY 0.617021 (-10185 4510);
PAINT ORANGE (-10185 4510);
FORCEPROP 2 LASTPIN (-10175 4150) $PN 10
J 2
(-10185 4160);
DISPLAY 0.617021 (-10185 4160);
PAINT ORANGE (-10185 4160);
FORCEPROP 1 LAST LOCATION EU8A1
J 0
(-10125 4675);
DISPLAY 0.617021 (-10125 4675);
PAINT AQUA (-10125 4675);
FORCEPROP 2 LASTPIN (-10175 4350) $PN 21
J 2
(-10185 4360);
DISPLAY 0.617021 (-10185 4360);
PAINT ORANGE (-10185 4360);
FORCEPROP 2 LASTPIN (-9275 4050) $PN 17
J 0
(-9265 4060);
DISPLAY 0.617021 (-9265 4060);
PAINT ORANGE (-9265 4060);
FORCEPROP 2 LASTPIN (-9275 3950) $PN 3
J 0
(-9265 3960);
DISPLAY 0.617021 (-9265 3960);
PAINT ORANGE (-9265 3960);
FORCEPROP 2 LASTPIN (-9275 3750) $PN 31
J 0
(-9265 3760);
DISPLAY 0.617021 (-9265 3760);
PAINT ORANGE (-9265 3760);
FORCEPROP 2 LASTPIN (-9275 3700) $PN 18
J 0
(-9265 3710);
DISPLAY 0.617021 (-9265 3710);
PAINT ORANGE (-9265 3710);
FORCEPROP 2 LASTPIN (-9275 3650) $PN 14
J 0
(-9265 3660);
DISPLAY 0.617021 (-9265 3660);
PAINT ORANGE (-9265 3660);
FORCEPROP 2 LASTPIN (-9275 3300) $PN 1
J 0
(-9265 3310);
DISPLAY 0.617021 (-9265 3310);
PAINT ORANGE (-9265 3310);
FORCEPROP 2 LASTPIN (-9275 4350) $PN 12
J 0
(-9265 4360);
DISPLAY 0.617021 (-9265 4360);
PAINT ORANGE (-9265 4360);
FORCEPROP 1 LAST MATERIAL IC
J 0
(-10125 4625);
DISPLAY 0.617021 (-10125 4625);
PAINT SKYBLUE (-10125 4625);
FORCEPROP 1 LAST PART_NUMBER H89187-001
J 0
(-10125 2850);
DISPLAY 0.617021 (-10125 2850);
PAINT BLUE (-10125 2850);
FORCEPROP 2 LASTPIN (-10175 3350) $PN 6
J 2
(-10185 3360);
DISPLAY 0.617021 (-10185 3360);
PAINT ORANGE (-10185 3360);
FORCEPROP 1 LAST PATH I229
J 0
(-9625 4626);
PAINT WHITE (-9625 4626);
DISPLAY INVISIBLE (-9625 4626);
FORCEPROP 2 LAST CDS_LOCATION EU8A1
J 0
(-10125 4675);
DISPLAY 0.617021 (-10125 4675);
PAINT AQUA (-10125 4675);
DISPLAY INVISIBLE (-10125 4675);
FORCEPROP 2 LAST SEC 1
J 0
(-10125 4725);
DISPLAY 0.680851 (-10125 4725);
PAINT MONO (-10125 4725);
DISPLAY INVISIBLE (-10125 4725);
FORCEPROP 2 LAST SEC_TYPE QFN
J 0
(-10125 4725);
DISPLAY 1.021277 (-10125 4725);
PAINT ORANGE (-10125 4725);
DISPLAY INVISIBLE (-10125 4725);
FORCEPROP 1 LAST PACK_TYPE QFN
J 0
(-10125 4725);
PAINT SKYBLUE (-10125 4725);
DISPLAY INVISIBLE (-10125 4725);
FORCEPROP 2 LAST CDS_LIB mstr_controller
J 0
(-9725 3750);
PAINT ORANGE (-9725 3750);
DISPLAY INVISIBLE (-9725 3750);
FORCEPROP 1 LAST CDS_LMAN_SYM_OUTLINE -400,850,400,-850
J 0
(-9725 3750);
DISPLAY 0.468085 (-9725 3750);
PAINT GREEN (-9725 3750);
DISPLAY INVISIBLE (-9725 3750);
FORCEADD OFFPAGE..1
R 2
(-7100 3600);
FORCEPROP 2 LAST $XR0 119 
J 0
(-6914 3600);
DISPLAY 0.638298 (-6914 3600);
PAINT MONO (-6914 3600);
FORCEPROP 1 LAST COMMENT_BODY TRUE
J 2
(-7225 3500);
DISPLAY 1.170213 (-7225 3500);
PAINT GREEN (-7225 3500);
DISPLAY INVISIBLE (-7225 3500);
FORCEPROP 1 LAST OFFPAGE TRUE
J 2
(-7425 3475);
DISPLAY 1.170213 (-7425 3475);
PAINT GREEN (-7425 3475);
DISPLAY INVISIBLE (-7425 3475);
FORCEPROP 2 LAST ROOM PVNN_PCH_STBY
J 0
(-7525 3675);
DISPLAY 1.361702 (-7525 3675);
PAINT ORANGE (-7525 3675);
DISPLAY INVISIBLE (-7525 3675);
FORCEPROP 2 LAST CDS_LIB mstr_standard
J 0
(-7100 3600);
PAINT ORANGE (-7100 3600);
DISPLAY INVISIBLE (-7100 3600);
FORCEPROP 2 LAST PATH I232
J 0
(-6925 3675);
DISPLAY 1.021277 (-6925 3675);
PAINT ORANGE (-6925 3675);
DISPLAY INVISIBLE (-6925 3675);
FORCEADD OFFPAGE..1
R 2
(-7125 3650);
FORCEPROP 2 LAST $XR0 119 
J 0
(-6939 3650);
DISPLAY 0.638298 (-6939 3650);
PAINT MONO (-6939 3650);
FORCEPROP 1 LAST COMMENT_BODY TRUE
J 2
(-7250 3550);
DISPLAY 1.170213 (-7250 3550);
PAINT GREEN (-7250 3550);
DISPLAY INVISIBLE (-7250 3550);
FORCEPROP 1 LAST OFFPAGE TRUE
J 2
(-7450 3525);
DISPLAY 1.170213 (-7450 3525);
PAINT GREEN (-7450 3525);
DISPLAY INVISIBLE (-7450 3525);
FORCEPROP 2 LAST ROOM PVNN_PCH_STBY
J 0
(-7550 3725);
DISPLAY 1.361702 (-7550 3725);
PAINT ORANGE (-7550 3725);
DISPLAY INVISIBLE (-7550 3725);
FORCEPROP 2 LAST CDS_LIB mstr_standard
J 0
(-7125 3650);
PAINT ORANGE (-7125 3650);
DISPLAY INVISIBLE (-7125 3650);
FORCEPROP 2 LAST PATH I234
J 0
(-6950 3725);
DISPLAY 1.021277 (-6950 3725);
PAINT ORANGE (-6950 3725);
DISPLAY INVISIBLE (-6950 3725);
FORCEADD SC22P50V2JN-4GP..1
R 1
(-11800 4450);
FORCEPROP 0 LAST GROUP POWER_FAIR
J 0
(-11947 4363);
DISPLAY 0.638298 (-11947 4363);
PAINT BROWN (-11947 4363);
DISPLAY BOTH (-11947 4363);
FORCEPROP 1 LAST LOCATION CF23
J 0
(-11955 4550);
DISPLAY 0.617021 (-11955 4550);
PAINT GREEN (-11955 4550);
FORCEPROP 2 LAST TYPE NPO
J 0
(-11550 4500);
DISPLAY 0.638298 (-11550 4500);
PAINT GREEN (-11550 4500);
FORCEPROP 2 LAST TOLERANCE 5%
J 0
(-11400 4550);
DISPLAY 0.638298 (-11400 4550);
PAINT GREEN (-11400 4550);
FORCEPROP 2 LAST PACK_SIZE 0402
J 0
(-11400 4500);
DISPLAY 0.638298 (-11400 4500);
PAINT GREEN (-11400 4500);
FORCEPROP 2 LAST ATTRIBUTE 22PF
J 0
(-11550 4550);
DISPLAY 0.638298 (-11550 4550);
PAINT GREEN (-11550 4550);
FORCEPROP 1 LAST VALUE SC22P50V2JN-4GP
J 0
(-11950 4500);
DISPLAY 0.617021 (-11950 4500);
PAINT GREEN (-11950 4500);
FORCEPROP 2 LAST RATED 50V
J 0
(-11300 4550);
DISPLAY 0.638298 (-11300 4550);
PAINT GREEN (-11300 4550);
FORCEPROP 1 LAST PART_NUMBER 78.22034.1FL
R 1
J 0
(-11800 4450);
DISPLAY 0.617021 (-11800 4450);
PAINT GREEN (-11800 4450);
DISPLAY INVISIBLE (-11800 4450);
FORCEPROP 1 LAST PACK_TYPE SMD-BCG
R 1
J 0
(-11800 4450);
DISPLAY 0.617021 (-11800 4450);
PAINT GREEN (-11800 4450);
DISPLAY INVISIBLE (-11800 4450);
FORCEPROP 1 LAST PATH I239
R 1
J 0
(-11800 4450);
DISPLAY 0.617021 (-11800 4450);
PAINT GREEN (-11800 4450);
DISPLAY INVISIBLE (-11800 4450);
FORCEPROP 1 LAST CDS_LMAN_SYM_OUTLINE -50,25,50,-25
R 1
J 0
(-11800 4450);
DISPLAY 0.468085 (-11800 4450);
PAINT GREEN (-11800 4450);
DISPLAY INVISIBLE (-11800 4450);
FORCEPROP 2 LAST CDS_LIB w_hdl
J 0
(-11800 4450);
PAINT MONO (-11800 4450);
DISPLAY INVISIBLE (-11800 4450);
FORCEADD SC22P50V2JN-4GP..1
R 1
(-11100 2900);
FORCEPROP 0 LAST GROUP POWER_FAIR
J 0
(-11247 2838);
DISPLAY 0.638298 (-11247 2838);
PAINT BROWN (-11247 2838);
DISPLAY BOTH (-11247 2838);
FORCEPROP 1 LAST VALUE SC22P50V2JN-4GP
J 0
(-11250 2750);
DISPLAY 0.617021 (-11250 2750);
PAINT GREEN (-11250 2750);
FORCEPROP 2 LAST ATTRIBUTE 22PF
J 0
(-11250 2700);
DISPLAY 0.638298 (-11250 2700);
PAINT GREEN (-11250 2700);
FORCEPROP 2 LAST TOLERANCE 5%
J 0
(-11250 2650);
DISPLAY 0.638298 (-11250 2650);
PAINT GREEN (-11250 2650);
FORCEPROP 1 LAST LOCATION CF24
J 0
(-11255 2800);
DISPLAY 0.617021 (-11255 2800);
PAINT GREEN (-11255 2800);
FORCEPROP 2 LAST TYPE NPO
J 0
(-11250 2550);
DISPLAY 0.638298 (-11250 2550);
PAINT GREEN (-11250 2550);
FORCEPROP 2 LAST RATED 50V
J 0
(-11250 2600);
DISPLAY 0.638298 (-11250 2600);
PAINT GREEN (-11250 2600);
FORCEPROP 2 LAST PACK_SIZE 0402
J 0
(-11100 2700);
DISPLAY 0.638298 (-11100 2700);
PAINT GREEN (-11100 2700);
FORCEPROP 1 LAST PART_NUMBER 78.22034.1FL
R 1
J 0
(-11100 2900);
DISPLAY 0.617021 (-11100 2900);
PAINT GREEN (-11100 2900);
DISPLAY INVISIBLE (-11100 2900);
FORCEPROP 1 LAST PACK_TYPE SMD-BCG
R 1
J 0
(-11100 2900);
DISPLAY 0.617021 (-11100 2900);
PAINT GREEN (-11100 2900);
DISPLAY INVISIBLE (-11100 2900);
FORCEPROP 1 LAST CDS_LMAN_SYM_OUTLINE -50,25,50,-25
R 1
J 0
(-11100 2900);
DISPLAY 0.468085 (-11100 2900);
PAINT GREEN (-11100 2900);
DISPLAY INVISIBLE (-11100 2900);
FORCEPROP 1 LAST PATH I240
R 1
J 0
(-11100 2900);
DISPLAY 0.617021 (-11100 2900);
PAINT GREEN (-11100 2900);
DISPLAY INVISIBLE (-11100 2900);
FORCEPROP 2 LAST CDS_LIB w_hdl
J 0
(-11100 2900);
PAINT MONO (-11100 2900);
DISPLAY INVISIBLE (-11100 2900);
FORCEADD RES..1
(-11775 4650);
FORCEPROP 1 LAST LOCATION RF23
J 0
(-12025 4750);
DISPLAY 0.617021 (-12025 4750);
PAINT AQUA (-12025 4750);
FORCEPROP 1 LAST VALUE 1.0K
J 2
(-11950 4700);
DISPLAY 0.617021 (-11950 4700);
PAINT SKYBLUE (-11950 4700);
FORCEPROP 1 LAST PACK_TYPE 0402
J 0
(-11650 4700);
DISPLAY 0.617021 (-11650 4700);
PAINT SKYBLUE (-11650 4700);
FORCEPROP 1 LAST PART_NUMBER G85996-004
J 0
(-11900 4750);
DISPLAY 0.617021 (-11900 4750);
PAINT BLUE (-11900 4750);
FORCEPROP 1 LAST TOLERANCE 0.1%
J 0
(-11925 4700);
DISPLAY 0.617021 (-11925 4700);
PAINT SKYBLUE (-11925 4700);
FORCEPROP 1 LASTPIN (-11875 4650) $PN 1
J 0
(-11863 4662);
DISPLAY 0.787234 (-11863 4662);
PAINT ORANGE (-11863 4662);
FORCEPROP 1 LASTPIN (-11675 4650) $PN 2
J 0
(-11713 4662);
DISPLAY 0.787234 (-11713 4662);
PAINT ORANGE (-11713 4662);
FORCEPROP 1 LAST WATTAGE 1/16W
J 2
(-11675 4700);
DISPLAY 0.617021 (-11675 4700);
PAINT SKYBLUE (-11675 4700);
FORCEPROP 1 LAST MATERIAL CHIP
J 0
(-11650 4750);
DISPLAY 0.617021 (-11650 4750);
PAINT SKYBLUE (-11650 4750);
FORCEPROP 0 LAST GROUP POWER_FAIR
J 0
(-11950 4600);
DISPLAY 0.638298 (-11950 4600);
PAINT BROWN (-11950 4600);
DISPLAY BOTH (-11950 4600);
FORCEPROP 2 LAST SEC_TYPE 0402
J 0
(-11825 4850);
DISPLAY 1.021277 (-11825 4850);
PAINT ORANGE (-11825 4850);
DISPLAY INVISIBLE (-11825 4850);
FORCEPROP 0 LAST SEC 1
J 0
(-11700 4800);
DISPLAY 0.680851 (-11700 4800);
PAINT MONO (-11700 4800);
DISPLAY INVISIBLE (-11700 4800);
FORCEPROP 1 LAST PATH I241
J 0
(-11825 4800);
DISPLAY 0.978723 (-11825 4800);
PAINT WHITE (-11825 4800);
DISPLAY INVISIBLE (-11825 4800);
FORCEPROP 2 LAST CDS_LIB mstr_discrete
J 0
(-11775 4650);
PAINT MONO (-11775 4650);
DISPLAY INVISIBLE (-11775 4650);
FORCEPROP 0 LAST ROOM SB
J 0
(-11725 4875);
DISPLAY 1.021277 (-11725 4875);
PAINT ORANGE (-11725 4875);
DISPLAY INVISIBLE (-11725 4875);
FORCEADD RES..1
(-11100 3000);
FORCEPROP 1 LAST MATERIAL CHIP
J 0
(-10900 3050);
DISPLAY 0.617021 (-10900 3050);
PAINT SKYBLUE (-10900 3050);
FORCEPROP 1 LAST VALUE 1.0K
J 2
(-11100 3125);
DISPLAY 0.617021 (-11100 3125);
PAINT SKYBLUE (-11100 3125);
FORCEPROP 1 LAST LOCATION RF24
J 0
(-11300 3125);
DISPLAY 0.617021 (-11300 3125);
PAINT AQUA (-11300 3125);
FORCEPROP 1 LASTPIN (-11200 3000) $PN 1
J 0
(-11188 3012);
DISPLAY 0.787234 (-11188 3012);
PAINT ORANGE (-11188 3012);
FORCEPROP 1 LAST PART_NUMBER G85996-004
J 0
(-11300 3050);
DISPLAY 0.617021 (-11300 3050);
PAINT BLUE (-11300 3050);
FORCEPROP 1 LAST TOLERANCE 0.1%
J 0
(-11050 3125);
DISPLAY 0.617021 (-11050 3125);
PAINT SKYBLUE (-11050 3125);
FORCEPROP 1 LAST PACK_TYPE 0402
J 0
(-10900 3125);
DISPLAY 0.617021 (-10900 3125);
PAINT SKYBLUE (-10900 3125);
FORCEPROP 1 LAST WATTAGE 1/16W
J 2
(-10925 3050);
DISPLAY 0.617021 (-10925 3050);
PAINT SKYBLUE (-10925 3050);
FORCEPROP 1 LASTPIN (-11000 3000) $PN 2
J 0
(-11038 3012);
DISPLAY 0.787234 (-11038 3012);
PAINT ORANGE (-11038 3012);
FORCEPROP 0 LAST GROUP POWER_FAIR
J 0
(-11250 2950);
DISPLAY 0.638298 (-11250 2950);
PAINT BROWN (-11250 2950);
DISPLAY BOTH (-11250 2950);
FORCEPROP 0 LAST SEC 1
J 0
(-11025 3150);
DISPLAY 0.680851 (-11025 3150);
PAINT MONO (-11025 3150);
DISPLAY INVISIBLE (-11025 3150);
FORCEPROP 2 LAST SEC_TYPE 0402
J 0
(-11150 3200);
DISPLAY 1.021277 (-11150 3200);
PAINT ORANGE (-11150 3200);
DISPLAY INVISIBLE (-11150 3200);
FORCEPROP 0 LAST ROOM SB
J 0
(-11050 3225);
DISPLAY 1.021277 (-11050 3225);
PAINT ORANGE (-11050 3225);
DISPLAY INVISIBLE (-11050 3225);
FORCEPROP 2 LAST CDS_LIB mstr_discrete
J 0
(-11100 3000);
PAINT MONO (-11100 3000);
DISPLAY INVISIBLE (-11100 3000);
FORCEPROP 1 LAST PATH I242
J 0
(-11150 3150);
DISPLAY 0.978723 (-11150 3150);
PAINT WHITE (-11150 3150);
DISPLAY INVISIBLE (-11150 3150);
FORCEADD GND..1
(-12200 3500);
FORCEPROP 3 LASTPIN (-12200 3550) SIG_NAME GND\g
J 0
(-12190 3560);
DISPLAY 0.659574 (-12190 3560);
PAINT MONO (-12190 3560);
DISPLAY INVISIBLE (-12190 3560);
FORCEPROP 1 LAST HDL_POWER GND
J 0
(-12200 3650);
DISPLAY 1.170213 (-12200 3650);
PAINT GREEN (-12200 3650);
DISPLAY INVISIBLE (-12200 3650);
FORCEPROP 1 LAST BODY_TYPE PLUMBING
J 0
(-12245 3457);
DISPLAY 0.340426 (-12245 3457);
PAINT GREEN (-12245 3457);
DISPLAY INVISIBLE (-12245 3457);
FORCEPROP 2 LAST CDS_LIB mstr_symbols
J 0
(-12200 3500);
PAINT ORANGE (-12200 3500);
DISPLAY INVISIBLE (-12200 3500);
FORCEPROP 1 LAST VOLTAGE 0
J 0
(-12200 3500);
PAINT SKYBLUE (-12200 3500);
DISPLAY INVISIBLE (-12200 3500);
FORCEPROP 2 LAST ROOM PVCCIN_CPU0_VR
J 0
(-12775 3575);
DISPLAY 1.361702 (-12775 3575);
PAINT ORANGE (-12775 3575);
DISPLAY INVISIBLE (-12775 3575);
FORCEPROP 1 LAST SIZE 1B
J 0
(-12125 3450);
DISPLAY 1.170213 (-12125 3450);
PAINT AQUA (-12125 3450);
DISPLAY INVISIBLE (-12125 3450);
FORCEPROP 1 LAST PATH I243
J 0
(-12125 3500);
DISPLAY 0.872340 (-12125 3500);
PAINT AQUA (-12125 3500);
DISPLAY INVISIBLE (-12125 3500);
FORCEADD CAP..1
(-12200 3700);
FORCEPROP 1 LAST MATERIAL X7R
J 0
(-12400 3675);
DISPLAY 0.617021 (-12400 3675);
PAINT SKYBLUE (-12400 3675);
FORCEPROP 1 LAST VOLTAGE 50V
J 0
(-12525 3675);
DISPLAY 0.617021 (-12525 3675);
PAINT SKYBLUE (-12525 3675);
FORCEPROP 1 LAST VALUE 220PF
J 0
(-12525 3725);
DISPLAY 0.617021 (-12525 3725);
PAINT SKYBLUE (-12525 3725);
FORCEPROP 1 LAST LOCATION C4W3
J 0
(-12525 3775);
DISPLAY 0.617021 (-12525 3775);
PAINT AQUA (-12525 3775);
FORCEPROP 1 LAST TOLERANCE 10%
J 0
(-12350 3725);
DISPLAY 0.617021 (-12350 3725);
PAINT SKYBLUE (-12350 3725);
FORCEPROP 1 LASTPIN (-12200 3800) $PN 1
J 0
(-12190 3780);
DISPLAY 0.617021 (-12190 3780);
PAINT ORANGE (-12190 3780);
FORCEPROP 1 LAST PACK_TYPE 0402LF
J 0
(-12525 3575);
DISPLAY 0.617021 (-12525 3575);
PAINT SKYBLUE (-12525 3575);
FORCEPROP 1 LASTPIN (-12200 3600) $PN 2
J 0
(-12190 3580);
DISPLAY 0.617021 (-12190 3580);
PAINT ORANGE (-12190 3580);
FORCEPROP 1 LAST PART_NUMBER A36096-050
J 0
(-12525 3625);
DISPLAY 0.617021 (-12525 3625);
PAINT BLUE (-12525 3625);
FORCEPROP 2 LAST CDS_LOCATION C4W3
J 0
(-12150 3800);
DISPLAY 0.617021 (-12150 3800);
PAINT AQUA (-12150 3800);
DISPLAY INVISIBLE (-12150 3800);
FORCEPROP 0 LAST CDS_SEC 1
J 0
(-12150 3850);
PAINT MONO (-12150 3850);
DISPLAY INVISIBLE (-12150 3850);
FORCEPROP 2 LAST CDS_LIB mstr_discrete
J 0
(-12200 3700);
PAINT ORANGE (-12200 3700);
DISPLAY INVISIBLE (-12200 3700);
FORCEPROP 2 LAST ROOM PVCCIN_CPU0_VR
J 0
(-12150 3850);
DISPLAY 1.361702 (-12150 3850);
PAINT ORANGE (-12150 3850);
DISPLAY INVISIBLE (-12150 3850);
FORCEPROP 2 LAST SEC 1
J 0
(-12150 3900);
DISPLAY 0.680851 (-12150 3900);
PAINT MONO (-12150 3900);
DISPLAY INVISIBLE (-12150 3900);
FORCEPROP 2 LAST SEC_TYPE 0402LF
J 0
(-12150 3900);
DISPLAY 1.021277 (-12150 3900);
PAINT ORANGE (-12150 3900);
DISPLAY INVISIBLE (-12150 3900);
FORCEPROP 1 LAST PATH I244
J 0
(-12150 3850);
DISPLAY 0.978723 (-12150 3850);
PAINT WHITE (-12150 3850);
DISPLAY INVISIBLE (-12150 3850);
FORCEADD GND..1
(-10000 2150);
FORCEPROP 3 LASTPIN (-10000 2200) SIG_NAME GND\g
J 0
(-9990 2210);
DISPLAY 0.659574 (-9990 2210);
PAINT MONO (-9990 2210);
DISPLAY INVISIBLE (-9990 2210);
FORCEPROP 1 LAST HDL_POWER GND
J 0
(-10000 2300);
DISPLAY 1.170213 (-10000 2300);
PAINT GREEN (-10000 2300);
DISPLAY INVISIBLE (-10000 2300);
FORCEPROP 1 LAST BODY_TYPE PLUMBING
J 0
(-10045 2107);
DISPLAY 0.340426 (-10045 2107);
PAINT GREEN (-10045 2107);
DISPLAY INVISIBLE (-10045 2107);
FORCEPROP 2 LAST CDS_LIB mstr_symbols
J 0
(-10000 2150);
PAINT ORANGE (-10000 2150);
DISPLAY INVISIBLE (-10000 2150);
FORCEPROP 1 LAST VOLTAGE 0
J 0
(-10000 2150);
PAINT SKYBLUE (-10000 2150);
DISPLAY INVISIBLE (-10000 2150);
FORCEPROP 2 LAST ROOM PVCCIN_CPU0_VR
J 0
(-10575 2225);
DISPLAY 1.361702 (-10575 2225);
PAINT ORANGE (-10575 2225);
DISPLAY INVISIBLE (-10575 2225);
FORCEPROP 1 LAST SIZE 1B
J 0
(-9925 2100);
DISPLAY 1.170213 (-9925 2100);
PAINT AQUA (-9925 2100);
DISPLAY INVISIBLE (-9925 2100);
FORCEPROP 1 LAST PATH I245
J 0
(-9925 2150);
DISPLAY 0.872340 (-9925 2150);
PAINT AQUA (-9925 2150);
DISPLAY INVISIBLE (-9925 2150);
FORCEADD CAP..1
(-10000 2350);
FORCEPROP 1 LAST PACK_TYPE 0402LF
J 0
(-9925 2225);
DISPLAY 0.617021 (-9925 2225);
PAINT SKYBLUE (-9925 2225);
FORCEPROP 1 LAST PART_NUMBER A36096-050
J 0
(-9925 2275);
DISPLAY 0.617021 (-9925 2275);
PAINT BLUE (-9925 2275);
FORCEPROP 1 LAST VOLTAGE 50V
J 0
(-9925 2325);
DISPLAY 0.617021 (-9925 2325);
PAINT SKYBLUE (-9925 2325);
FORCEPROP 1 LASTPIN (-10000 2450) $PN 1
J 0
(-9990 2430);
DISPLAY 0.617021 (-9990 2430);
PAINT ORANGE (-9990 2430);
FORCEPROP 1 LAST LOCATION C4W4
J 0
(-9925 2425);
DISPLAY 0.617021 (-9925 2425);
PAINT AQUA (-9925 2425);
FORCEPROP 1 LAST MATERIAL X7R
J 0
(-9800 2325);
DISPLAY 0.617021 (-9800 2325);
PAINT SKYBLUE (-9800 2325);
FORCEPROP 1 LASTPIN (-10000 2250) $PN 2
J 0
(-9990 2230);
DISPLAY 0.617021 (-9990 2230);
PAINT ORANGE (-9990 2230);
FORCEPROP 1 LAST TOLERANCE 10%
J 0
(-9750 2375);
DISPLAY 0.617021 (-9750 2375);
PAINT SKYBLUE (-9750 2375);
FORCEPROP 1 LAST VALUE 220PF
J 0
(-9925 2375);
DISPLAY 0.617021 (-9925 2375);
PAINT SKYBLUE (-9925 2375);
FORCEPROP 2 LAST CDS_LOCATION C4W4
J 0
(-9950 2450);
DISPLAY 0.617021 (-9950 2450);
PAINT AQUA (-9950 2450);
DISPLAY INVISIBLE (-9950 2450);
FORCEPROP 0 LAST CDS_SEC 1
J 0
(-9950 2500);
PAINT MONO (-9950 2500);
DISPLAY INVISIBLE (-9950 2500);
FORCEPROP 2 LAST CDS_LIB mstr_discrete
J 0
(-10000 2350);
PAINT ORANGE (-10000 2350);
DISPLAY INVISIBLE (-10000 2350);
FORCEPROP 2 LAST ROOM PVCCIN_CPU0_VR
J 0
(-9950 2500);
DISPLAY 1.361702 (-9950 2500);
PAINT ORANGE (-9950 2500);
DISPLAY INVISIBLE (-9950 2500);
FORCEPROP 2 LAST SEC 1
J 0
(-9950 2550);
DISPLAY 0.680851 (-9950 2550);
PAINT MONO (-9950 2550);
DISPLAY INVISIBLE (-9950 2550);
FORCEPROP 2 LAST SEC_TYPE 0402LF
J 0
(-9950 2550);
DISPLAY 1.021277 (-9950 2550);
PAINT ORANGE (-9950 2550);
DISPLAY INVISIBLE (-9950 2550);
FORCEPROP 1 LAST PATH I246
J 0
(-9950 2500);
DISPLAY 0.978723 (-9950 2500);
PAINT WHITE (-9950 2500);
DISPLAY INVISIBLE (-9950 2500);
FORCEADD RES..2
(-11100 4600);
FORCEPROP 1 LAST WATTAGE 1/16W
J 0
(-11060 4575);
DISPLAY 0.617021 (-11060 4575);
PAINT SKYBLUE (-11060 4575);
FORCEPROP 1 LAST PART_NUMBER G21796-026
J 0
(-11060 4475);
DISPLAY 0.617021 (-11060 4475);
PAINT BLUE (-11060 4475);
FORCEPROP 1 LAST TOLERANCE 1%
J 0
(-11055 4625);
DISPLAY 0.617021 (-11055 4625);
PAINT SKYBLUE (-11055 4625);
FORCEPROP 1 LAST MATERIAL CHIP
J 0
(-11060 4525);
DISPLAY 0.617021 (-11060 4525);
PAINT SKYBLUE (-11060 4525);
FORCEPROP 1 LAST PACK_TYPE 0402
J 0
(-11060 4425);
DISPLAY 0.617021 (-11060 4425);
PAINT SKYBLUE (-11060 4425);
FORCEPROP 1 LASTPIN (-11100 4500) $PN 2
J 0
(-11095 4510);
DISPLAY 0.617021 (-11095 4510);
PAINT ORANGE (-11095 4510);
FORCEPROP 1 LASTPIN (-11100 4700) $PN 1
J 0
(-11095 4662);
DISPLAY 0.617021 (-11095 4662);
PAINT ORANGE (-11095 4662);
FORCEPROP 1 LAST VALUE 1.00K
J 0
(-11055 4675);
DISPLAY 0.617021 (-11055 4675);
PAINT SKYBLUE (-11055 4675);
FORCEPROP 1 LAST LOCATION R8W2
J 0
(-11055 4725);
DISPLAY 0.617021 (-11055 4725);
PAINT AQUA (-11055 4725);
FORCEPROP 2 LAST CDS_LOCATION R8W2
J 0
(-11055 4725);
DISPLAY 0.617021 (-11055 4725);
PAINT AQUA (-11055 4725);
DISPLAY INVISIBLE (-11055 4725);
FORCEPROP 1 LAST PATH I247
J 0
(-11050 4775);
DISPLAY 0.978723 (-11050 4775);
PAINT WHITE (-11050 4775);
DISPLAY INVISIBLE (-11050 4775);
FORCEPROP 2 LAST SEC_TYPE 0402
J 0
(-11050 4825);
DISPLAY 1.021277 (-11050 4825);
PAINT ORANGE (-11050 4825);
DISPLAY INVISIBLE (-11050 4825);
FORCEPROP 2 LAST ROOM PVNN_PCH_STBY
J 0
(-11050 4775);
DISPLAY 1.361702 (-11050 4775);
PAINT ORANGE (-11050 4775);
DISPLAY INVISIBLE (-11050 4775);
FORCEPROP 0 LAST SEC 1
J 0
(-11050 4775);
DISPLAY 0.680851 (-11050 4775);
PAINT MONO (-11050 4775);
DISPLAY INVISIBLE (-11050 4775);
FORCEPROP 2 LAST CDS_LIB mstr_discrete
J 0
(-11100 4600);
PAINT ORANGE (-11100 4600);
DISPLAY INVISIBLE (-11100 4600);
FORCEADD RES..2
(-11800 3750);
FORCEPROP 1 LASTPIN (-11800 3850) $PN 1
J 0
(-11795 3812);
DISPLAY 0.617021 (-11795 3812);
PAINT ORANGE (-11795 3812);
FORCEPROP 1 LASTPIN (-11800 3650) $PN 2
J 0
(-11795 3660);
DISPLAY 0.617021 (-11795 3660);
PAINT ORANGE (-11795 3660);
FORCEPROP 1 LAST TOLERANCE 1%
J 0
(-11755 3725);
DISPLAY 0.617021 (-11755 3725);
PAINT SKYBLUE (-11755 3725);
FORCEPROP 1 LAST VALUE 1.00K
J 0
(-11755 3775);
DISPLAY 0.617021 (-11755 3775);
PAINT SKYBLUE (-11755 3775);
FORCEPROP 1 LAST MATERIAL CHIP
J 0
(-11585 3825);
DISPLAY 0.617021 (-11585 3825);
PAINT SKYBLUE (-11585 3825);
FORCEPROP 1 LAST PART_NUMBER G21796-026
J 0
(-11585 3775);
DISPLAY 0.617021 (-11585 3775);
PAINT BLUE (-11585 3775);
FORCEPROP 1 LAST PACK_TYPE 0402
J 0
(-11585 3725);
DISPLAY 0.617021 (-11585 3725);
PAINT SKYBLUE (-11585 3725);
FORCEPROP 1 LAST WATTAGE 1/16W
J 0
(-11760 3675);
DISPLAY 0.617021 (-11760 3675);
PAINT SKYBLUE (-11760 3675);
FORCEPROP 1 LAST LOCATION R8W3
J 0
(-11755 3825);
DISPLAY 0.617021 (-11755 3825);
PAINT AQUA (-11755 3825);
FORCEPROP 2 LAST CDS_LOCATION R8W3
J 0
(-11755 3875);
DISPLAY 0.617021 (-11755 3875);
PAINT AQUA (-11755 3875);
DISPLAY INVISIBLE (-11755 3875);
FORCEPROP 2 LAST SEC_TYPE 0402
J 0
(-11750 3975);
DISPLAY 1.021277 (-11750 3975);
PAINT ORANGE (-11750 3975);
DISPLAY INVISIBLE (-11750 3975);
FORCEPROP 2 LAST ROOM PVNN_PCH_STBY
J 0
(-11750 3925);
DISPLAY 1.361702 (-11750 3925);
PAINT ORANGE (-11750 3925);
DISPLAY INVISIBLE (-11750 3925);
FORCEPROP 0 LAST SEC 1
J 0
(-11750 3925);
DISPLAY 0.680851 (-11750 3925);
PAINT MONO (-11750 3925);
DISPLAY INVISIBLE (-11750 3925);
FORCEPROP 2 LAST CDS_LIB mstr_discrete
J 0
(-11800 3750);
PAINT ORANGE (-11800 3750);
DISPLAY INVISIBLE (-11800 3750);
FORCEPROP 1 LAST PATH I248
J 0
(-11750 3925);
DISPLAY 0.978723 (-11750 3925);
PAINT WHITE (-11750 3925);
DISPLAY INVISIBLE (-11750 3925);
FORCEADD RES..2
(-8750 4950);
FORCEPROP 1 LAST PART_NUMBER G21796-026
J 0
(-8710 4825);
DISPLAY 0.617021 (-8710 4825);
PAINT BLUE (-8710 4825);
FORCEPROP 1 LASTPIN (-8750 5050) $PN 1
J 0
(-8745 5012);
DISPLAY 0.617021 (-8745 5012);
PAINT ORANGE (-8745 5012);
FORCEPROP 1 LAST TOLERANCE 1%
J 0
(-8705 4975);
DISPLAY 0.617021 (-8705 4975);
PAINT SKYBLUE (-8705 4975);
FORCEPROP 1 LAST WATTAGE 1/16W
J 0
(-8710 4925);
DISPLAY 0.617021 (-8710 4925);
PAINT SKYBLUE (-8710 4925);
FORCEPROP 1 LAST VALUE 1.00K
J 0
(-8705 5025);
DISPLAY 0.617021 (-8705 5025);
PAINT SKYBLUE (-8705 5025);
FORCEPROP 1 LAST LOCATION R8W8
J 0
(-8705 5075);
DISPLAY 0.617021 (-8705 5075);
PAINT AQUA (-8705 5075);
FORCEPROP 1 LASTPIN (-8750 4850) $PN 2
J 0
(-8745 4860);
DISPLAY 0.617021 (-8745 4860);
PAINT ORANGE (-8745 4860);
FORCEPROP 1 LAST MATERIAL CHIP
J 0
(-8710 4875);
DISPLAY 0.617021 (-8710 4875);
PAINT SKYBLUE (-8710 4875);
FORCEPROP 1 LAST PACK_TYPE 0402
J 0
(-8710 4775);
DISPLAY 0.617021 (-8710 4775);
PAINT SKYBLUE (-8710 4775);
FORCEPROP 2 LAST SEC_TYPE 0402
J 0
(-8700 5175);
DISPLAY 1.021277 (-8700 5175);
PAINT ORANGE (-8700 5175);
DISPLAY INVISIBLE (-8700 5175);
FORCEPROP 2 LAST ROOM PVNN_PCH_STBY
J 0
(-8700 5125);
DISPLAY 1.361702 (-8700 5125);
PAINT ORANGE (-8700 5125);
DISPLAY INVISIBLE (-8700 5125);
FORCEPROP 0 LAST SEC 1
J 0
(-8700 5125);
DISPLAY 0.680851 (-8700 5125);
PAINT MONO (-8700 5125);
DISPLAY INVISIBLE (-8700 5125);
FORCEPROP 2 LAST CDS_LIB mstr_discrete
J 0
(-8750 4950);
PAINT ORANGE (-8750 4950);
DISPLAY INVISIBLE (-8750 4950);
FORCEPROP 1 LAST PATH I249
J 0
(-8700 5125);
DISPLAY 0.978723 (-8700 5125);
PAINT WHITE (-8700 5125);
DISPLAY INVISIBLE (-8700 5125);
FORCEPROP 2 LAST CDS_LOCATION R8W8
J 0
(-8705 5075);
DISPLAY 0.617021 (-8705 5075);
PAINT AQUA (-8705 5075);
DISPLAY INVISIBLE (-8705 5075);
FORCEADD RES..2
(-7750 4950);
FORCEPROP 1 LAST MATERIAL CHIP
J 0
(-7710 4875);
DISPLAY 0.617021 (-7710 4875);
PAINT SKYBLUE (-7710 4875);
FORCEPROP 1 LAST VALUE 100.0K
J 0
(-7705 5025);
DISPLAY 0.617021 (-7705 5025);
PAINT SKYBLUE (-7705 5025);
FORCEPROP 1 LAST PART_NUMBER G21796-010
J 0
(-7710 4825);
DISPLAY 0.617021 (-7710 4825);
PAINT BLUE (-7710 4825);
FORCEPROP 1 LASTPIN (-7750 4850) $PN 2
J 0
(-7745 4860);
DISPLAY 0.787234 (-7745 4860);
PAINT ORANGE (-7745 4860);
FORCEPROP 1 LAST PACK_TYPE 0402
J 0
(-7710 4775);
DISPLAY 0.617021 (-7710 4775);
PAINT SKYBLUE (-7710 4775);
FORCEPROP 1 LASTPIN (-7750 5050) $PN 1
J 0
(-7745 5012);
DISPLAY 0.787234 (-7745 5012);
PAINT ORANGE (-7745 5012);
FORCEPROP 1 LAST TOLERANCE 1%
J 0
(-7705 4975);
DISPLAY 0.617021 (-7705 4975);
PAINT SKYBLUE (-7705 4975);
FORCEPROP 1 LAST WATTAGE 1/16W
J 0
(-7710 4925);
DISPLAY 0.617021 (-7710 4925);
PAINT SKYBLUE (-7710 4925);
FORCEPROP 1 LAST LOCATION R2L25
J 0
(-7705 5075);
DISPLAY 0.617021 (-7705 5075);
PAINT AQUA (-7705 5075);
FORCEPROP 0 LAST ROOM SB
J 0
(-7700 5175);
DISPLAY 1.021277 (-7700 5175);
PAINT ORANGE (-7700 5175);
DISPLAY INVISIBLE (-7700 5175);
FORCEPROP 1 LAST PATH I252
J 0
(-7700 5125);
DISPLAY 0.978723 (-7700 5125);
PAINT WHITE (-7700 5125);
DISPLAY INVISIBLE (-7700 5125);
FORCEPROP 2 LAST CDS_LIB mstr_discrete
J 0
(-7750 4950);
DISPLAY INVISIBLE (-7750 4950);
FORCEPROP 2 LAST SEC_TYPE 0402
J 0
(-7700 5175);
DISPLAY 1.021277 (-7700 5175);
PAINT ORANGE (-7700 5175);
DISPLAY INVISIBLE (-7700 5175);
FORCEPROP 2 LAST SEC 1
J 0
(-7700 5175);
DISPLAY 0.680851 (-7700 5175);
PAINT MONO (-7700 5175);
DISPLAY INVISIBLE (-7700 5175);
FORCEADD RES..2
(-7350 4950);
FORCEPROP 1 LAST PACK_TYPE 0402
J 0
(-7310 4775);
DISPLAY 0.617021 (-7310 4775);
PAINT SKYBLUE (-7310 4775);
FORCEPROP 1 LAST LOCATION R2L26
J 0
(-7305 5075);
DISPLAY 0.617021 (-7305 5075);
PAINT AQUA (-7305 5075);
FORCEPROP 1 LASTPIN (-7350 4850) $PN 2
J 0
(-7345 4860);
DISPLAY 0.787234 (-7345 4860);
PAINT ORANGE (-7345 4860);
FORCEPROP 1 LAST MATERIAL CHIP
J 0
(-7310 4875);
DISPLAY 0.617021 (-7310 4875);
PAINT SKYBLUE (-7310 4875);
FORCEPROP 1 LAST PART_NUMBER G21796-010
J 0
(-7310 4825);
DISPLAY 0.617021 (-7310 4825);
PAINT BLUE (-7310 4825);
FORCEPROP 1 LAST WATTAGE 1/16W
J 0
(-7310 4925);
DISPLAY 0.617021 (-7310 4925);
PAINT SKYBLUE (-7310 4925);
FORCEPROP 1 LAST TOLERANCE 1%
J 0
(-7305 4975);
DISPLAY 0.617021 (-7305 4975);
PAINT SKYBLUE (-7305 4975);
FORCEPROP 1 LASTPIN (-7350 5050) $PN 1
J 0
(-7345 5012);
DISPLAY 0.787234 (-7345 5012);
PAINT ORANGE (-7345 5012);
FORCEPROP 1 LAST VALUE 100.0K
J 0
(-7305 5025);
DISPLAY 0.617021 (-7305 5025);
PAINT SKYBLUE (-7305 5025);
FORCEPROP 0 LAST ROOM SB
J 0
(-7300 5175);
DISPLAY 1.021277 (-7300 5175);
PAINT ORANGE (-7300 5175);
DISPLAY INVISIBLE (-7300 5175);
FORCEPROP 2 LAST CDS_LIB mstr_discrete
J 0
(-7350 4950);
DISPLAY INVISIBLE (-7350 4950);
FORCEPROP 2 LAST SEC_TYPE 0402
J 0
(-7300 5175);
DISPLAY 1.021277 (-7300 5175);
PAINT ORANGE (-7300 5175);
DISPLAY INVISIBLE (-7300 5175);
FORCEPROP 2 LAST SEC 1
J 0
(-7300 5175);
DISPLAY 0.680851 (-7300 5175);
PAINT MONO (-7300 5175);
DISPLAY INVISIBLE (-7300 5175);
FORCEPROP 1 LAST PATH I253
J 0
(-7300 5125);
DISPLAY 0.978723 (-7300 5125);
PAINT WHITE (-7300 5125);
DISPLAY INVISIBLE (-7300 5125);
FORCEADD RES..2
(-10750 2150);
FORCEPROP 1 LAST VALUE 4.02K
J 0
(-10705 2225);
DISPLAY 0.617021 (-10705 2225);
PAINT SKYBLUE (-10705 2225);
FORCEPROP 1 LAST PART_NUMBER G21796-082
J 0
(-10710 2025);
DISPLAY 0.617021 (-10710 2025);
PAINT BLUE (-10710 2025);
FORCEPROP 1 LAST MATERIAL CHIP
J 0
(-10710 2075);
DISPLAY 0.617021 (-10710 2075);
PAINT SKYBLUE (-10710 2075);
FORCEPROP 1 LAST PACK_TYPE 0402
J 0
(-10710 1975);
DISPLAY 0.617021 (-10710 1975);
PAINT SKYBLUE (-10710 1975);
FORCEPROP 1 LAST TOLERANCE 1%
J 0
(-10705 2175);
DISPLAY 0.617021 (-10705 2175);
PAINT SKYBLUE (-10705 2175);
FORCEPROP 1 LAST WATTAGE 1/16W
J 0
(-10710 2125);
DISPLAY 0.617021 (-10710 2125);
PAINT SKYBLUE (-10710 2125);
FORCEPROP 1 LASTPIN (-10750 2050) $PN 2
J 0
(-10745 2060);
DISPLAY 0.617021 (-10745 2060);
PAINT ORANGE (-10745 2060);
FORCEPROP 1 LASTPIN (-10750 2250) $PN 1
J 0
(-10745 2212);
DISPLAY 0.617021 (-10745 2212);
PAINT ORANGE (-10745 2212);
FORCEPROP 1 LAST LOCATION R2L9
J 0
(-10705 2275);
DISPLAY 0.617021 (-10705 2275);
PAINT AQUA (-10705 2275);
FORCEPROP 2 LAST CDS_LOCATION R2L9
J 0
(-10705 2275);
DISPLAY 0.617021 (-10705 2275);
PAINT AQUA (-10705 2275);
DISPLAY INVISIBLE (-10705 2275);
FORCEPROP 0 LAST CDS_SEC 1
J 0
(-10700 2325);
DISPLAY INVISIBLE (-10700 2325);
FORCEPROP 2 LAST SEC_TYPE 0402
J 0
(-10700 2375);
DISPLAY 1.021277 (-10700 2375);
PAINT ORANGE (-10700 2375);
DISPLAY INVISIBLE (-10700 2375);
FORCEPROP 2 LAST SEC 1
J 0
(-10700 2375);
PAINT MONO (-10700 2375);
DISPLAY INVISIBLE (-10700 2375);
FORCEPROP 0 LAST ROOM PVCCIN_CPU0_VR
J 0
(-10700 2375);
DISPLAY 1.021277 (-10700 2375);
PAINT ORANGE (-10700 2375);
DISPLAY INVISIBLE (-10700 2375);
FORCEPROP 2 LAST CDS_LIB mstr_discrete
J 0
(-10750 2150);
PAINT ORANGE (-10750 2150);
DISPLAY INVISIBLE (-10750 2150);
FORCEPROP 1 LAST PATH I254
J 0
(-10700 2325);
DISPLAY 0.978723 (-10700 2325);
PAINT WHITE (-10700 2325);
DISPLAY INVISIBLE (-10700 2325);
FORCEADD CAP_A..1
(-12750 5150);
FORCEPROP 1 LAST PART_NUMBER A36096-030
J 0
(-12700 5000);
DISPLAY 0.617021 (-12700 5000);
PAINT BLUE (-12700 5000);
FORCEPROP 1 LAST MATERIAL X7R
J 0
(-12700 5050);
DISPLAY 0.617021 (-12700 5050);
PAINT SKYBLUE (-12700 5050);
FORCEPROP 1 LASTPIN (-12750 5050) $PN 2
J 0
(-12740 5030);
DISPLAY 0.787234 (-12740 5030);
PAINT ORANGE (-12740 5030);
FORCEPROP 1 LAST TOLERANCE 10%
J 0
(-12700 5100);
DISPLAY 0.617021 (-12700 5100);
PAINT SKYBLUE (-12700 5100);
FORCEPROP 1 LAST VOLTAGE 16V
J 0
(-12700 5150);
DISPLAY 0.617021 (-12700 5150);
PAINT SKYBLUE (-12700 5150);
FORCEPROP 1 LASTPIN (-12750 5250) $PN 1
J 0
(-12740 5230);
DISPLAY 0.787234 (-12740 5230);
PAINT ORANGE (-12740 5230);
FORCEPROP 1 LAST LOCATION C8A3
J 0
(-12700 5250);
DISPLAY 0.617021 (-12700 5250);
PAINT AQUA (-12700 5250);
FORCEPROP 1 LAST PACK_TYPE 0402V
J 0
(-12700 4950);
DISPLAY 0.617021 (-12700 4950);
PAINT SKYBLUE (-12700 4950);
FORCEPROP 1 LAST VALUE 0.1UF
J 0
(-12700 5200);
DISPLAY 0.617021 (-12700 5200);
PAINT SKYBLUE (-12700 5200);
FORCEPROP 0 LAST CDS_SEC 1
J 0
(-12700 5300);
PAINT MONO (-12700 5300);
DISPLAY INVISIBLE (-12700 5300);
FORCEPROP 2 LAST SEC 1
J 0
(-12700 5350);
DISPLAY 0.680851 (-12700 5350);
PAINT MONO (-12700 5350);
DISPLAY INVISIBLE (-12700 5350);
FORCEPROP 2 LAST SEC_TYPE 0402V
J 0
(-12700 5350);
DISPLAY 1.021277 (-12700 5350);
PAINT ORANGE (-12700 5350);
DISPLAY INVISIBLE (-12700 5350);
FORCEPROP 0 LAST ROOM CPU_FANS
J 0
(-12700 5350);
DISPLAY 1.021277 (-12700 5350);
PAINT ORANGE (-12700 5350);
DISPLAY INVISIBLE (-12700 5350);
FORCEPROP 0 LAST BOM_COST SM_THERM
J 0
(-12700 5300);
DISPLAY 1.021277 (-12700 5300);
PAINT ORANGE (-12700 5300);
DISPLAY INVISIBLE (-12700 5300);
FORCEPROP 2 LAST CDS_LIB dev_discrete
J 0
(-12750 5150);
PAINT MONO (-12750 5150);
DISPLAY INVISIBLE (-12750 5150);
FORCEPROP 1 LAST PATH I255
J 0
(-12700 5300);
DISPLAY 0.978723 (-12700 5300);
PAINT WHITE (-12700 5300);
DISPLAY INVISIBLE (-12700 5300);
FORCEPROP 0 LAST CDS_LOCATION C8A3
J 0
(-12700 5300);
PAINT MONO (-12700 5300);
DISPLAY INVISIBLE (-12700 5300);
FORCEADD DESIGN_NOTE..1
(-7050 2200);
FORCEPROP 0 LAST L22 1
J 0
(-7150 1650);
PAINT WHITE (-7150 1650);
FORCEPROP 0 LAST L31 1
J 0
(-6800 1575);
PAINT WHITE (-6800 1575);
FORCEPROP 0 LAST L23 0
J 0
(-6800 1650);
PAINT WHITE (-6800 1650);
FORCEPROP 0 LAST L15 1
J 0
(-6800 1775);
PAINT WHITE (-6800 1775);
FORCEPROP 0 LAST L14 0
J 0
(-7150 1750);
PAINT WHITE (-7150 1750);
FORCEPROP 0 LAST L6 0
J 0
(-7150 1850);
PAINT WHITE (-7150 1850);
FORCEPROP 0 LAST L7 0
J 0
(-6800 1850);
PAINT WHITE (-6800 1850);
FORCEPROP 0 LAST L30 1
J 0
(-7150 1550);
PAINT WHITE (-7150 1550);
FORCEPROP 0 LAST L17 0.900 V
J 0
(-6500 1750);
PAINT WHITE (-6500 1750);
FORCEPROP 0 LAST L5 OUTPUT VOLTAGE
J 0
(-6525 1950);
PAINT WHITE (-6525 1950);
FORCEPROP 0 LAST L9 0.850 V
J 0
(-6500 1850);
PAINT WHITE (-6500 1850);
FORCEPROP 0 LAST L33 1.000 V
J 0
(-6500 1550);
PAINT WHITE (-6500 1550);
FORCEPROP 0 LAST L25 0.950 V
J 0
(-6500 1650);
PAINT WHITE (-6500 1650);
FORCEPROP 0 LAST L2 AVID0
J 0
(-6900 1950);
PAINT WHITE (-6900 1950);
FORCEPROP 0 LAST L1 OUTPUT VOLTAGE AVID
J 0
(-7250 2075);
PAINT WHITE (-7250 2075);
FORCEPROP 0 LAST L3 AVID1
J 0
(-7250 1950);
PAINT WHITE (-7250 1950);
FORCEPROP 1 LAST COMMENT_BODY TRUE
J 0
(-7025 2300);
DISPLAY 1.319149 (-7025 2300);
PAINT ORANGE (-7025 2300);
DISPLAY INVISIBLE (-7025 2300);
FORCEPROP 2 LAST CDS_LIB mstr_symbols
J 0
(-7050 2200);
PAINT ORANGE (-7050 2200);
DISPLAY INVISIBLE (-7050 2200);
FORCEADD DNS..2
(-11170 5070);
PAINT RED (-11170 5070);
FORCEPROP 2 LAST CDS_LIB mstr_misc
J 0
(-11170 5070);
PAINT ORANGE (-11170 5070);
DISPLAY INVISIBLE (-11170 5070);
FORCEPROP 1 LAST COMMENT_BODY TRUE
R 1
J 0
(-11095 4845);
DISPLAY 0.872340 (-11095 4845);
PAINT GREEN (-11095 4845);
DISPLAY INVISIBLE (-11095 4845);
FORCEADD INTEL_CORP_BPAGE..1
(-5800 1000);
FORCEPROP 1 LAST CDS_CON_LAST_MODIFIED Fri Jun 16 17:49:24 2017
J 0
(-7225 1325);
PAINT ORANGE (-7225 1325);
DISPLAY INVISIBLE (-7225 1325);
FORCEPROP 1 LAST CUSTOM_TXT_CDS <CURRENT_DESIGN_SHEET> OF <TOTAL_DESIGN_SHEETS>
J 0
(-6300 1025);
PAINT ORANGE (-6300 1025);
FORCEPROP 1 LAST CUSTOM_TXT_CDS <CON_LAST_MODIFIED>
J 0
(-9800 1100);
PAINT ORANGE (-9800 1100);
FORCEPROP 2 LAST CUSTOM_TXT_CDS <XR_PAGE_TITLE>
J 0
(-13690 6250);
DISPLAY 0.638298 (-13690 6250);
PAINT PINK (-13690 6250);
DISPLAY INVISIBLE (-13690 6250);
FORCEPROP 1 LAST SCH_TITLE PVNN P1V05 PCH STBY VR (1 OF 2)
J 0
(-13650 1125);
DISPLAY 1.212766 (-13650 1125);
PAINT ORANGE (-13650 1125);
FORCEPROP 1 LAST COMMENT_BODY TRUE
J 0
(-5788 1012);
DISPLAY 0.468085 (-5788 1012);
PAINT GREEN (-5788 1012);
DISPLAY INVISIBLE (-5788 1012);
FORCEPROP 2 LAST PAGE_BORDER TRUE
J 0
(-13690 6250);
DISPLAY 0.851064 (-13690 6250);
PAINT PINK (-13690 6250);
DISPLAY INVISIBLE (-13690 6250);
FORCEPROP 2 LAST CDS_LIB mstr_symbols
J 0
(-5800 1000);
PAINT ORANGE (-5800 1000);
DISPLAY INVISIBLE (-5800 1000);
FORCEPROP 2 LAST CDS_XR_PAGE_TITLE CR-235 : @BASEBOARD_FAB2_LIB.BASEBOARD_FAB2(SCH_1):PAGE235
J 0
(-13690 6250);
DISPLAY 0.638298 (-13690 6250);
PAINT PINK (-13690 6250);
DISPLAY INVISIBLE (-13690 6250);
FORCEADD DESIGN_NOTE..1
(-9700 2725);
FORCEPROP 0 LAST L1 SMBUS ADDRESS: 0XD0
J 0
(-9900 2600);
DISPLAY 1.021277 (-9900 2600);
PAINT VIOLET (-9900 2600);
FORCEPROP 2 LAST CDS_LIB mstr_symbols
J 0
(-9700 2725);
PAINT ORANGE (-9700 2725);
DISPLAY INVISIBLE (-9700 2725);
FORCEPROP 1 LAST COMMENT_BODY TRUE
J 0
(-9675 2825);
DISPLAY 0.978723 (-9675 2825);
PAINT ORANGE (-9675 2825);
DISPLAY INVISIBLE (-9675 2825);
FORCEADD DNS..2
(-8395 4945);
PAINT RED (-8395 4945);
FORCEPROP 2 LAST CDS_LIB mstr_misc
J 0
(-8395 4945);
PAINT ORANGE (-8395 4945);
DISPLAY INVISIBLE (-8395 4945);
FORCEPROP 1 LAST COMMENT_BODY TRUE
R 1
J 0
(-8320 4720);
DISPLAY 0.872340 (-8320 4720);
PAINT GREEN (-8320 4720);
DISPLAY INVISIBLE (-8320 4720);
WIRE 16 -1 (-8400 5250)(-8400 5200);
WIRE 16 -1 (-8075 5200)(-8400 5200);
WIRE 16 -1 (-8750 5200)(-8400 5200);
WIRE 16 -1 (-8400 5050)(-8400 5200);
WIRE 16 -1 (-9100 5200)(-8750 5200);
WIRE 16 -1 (-8750 5200)(-8750 5050);
WIRE 16 -1 (-8075 5200)(-7750 5200);
WIRE 16 -1 (-8075 5050)(-8075 5200);
WIRE 16 -1 (-7350 5200)(-7750 5200);
WIRE 16 -1 (-7750 5200)(-7750 5050);
WIRE 16 -1 (-9100 5050)(-9100 5200);
WIRE 16 -1 (-7350 5200)(-7350 5050);
WIRE 16 -1 (-8800 1800)(-8800 1875);
WIRE 16 -1 (-9200 1825)(-9200 1875);
WIRE 16 -1 (-9750 4925)(-9750 4975);
WIRE 16 -1 (-8900 3000)(-8900 2850);
WIRE 16 -1 (-8900 3050)(-8900 3000);
WIRE 16 -1 (-9275 3000)(-8900 3000);
WIRE 16 -1 (-8900 3050)(-8900 3200);
WIRE 16 -1 (-9275 3050)(-8900 3050);
WIRE 16 -1 (-9275 3200)(-8900 3200);
WIRE 16 -1 (-10450 5600)(-10450 5700);
WIRE 16 -1 (-11175 5600)(-10450 5600);
WIRE 16 -1 (-10450 5525)(-10450 5600);
WIRE 16 -1 (-11175 5175)(-11175 5600);
WIRE 16 -1 (-10150 4925)(-10150 4975);
WIRE 16 -1 (-10750 1950)(-10750 1900);
WIRE 16 -1 (-10450 1950)(-10750 1950);
WIRE 16 -1 (-10750 2050)(-10750 1950);
WIRE 16 -1 (-10450 2050)(-10450 1950);
WIRE 16 -1 (-12325 4975)(-12325 5075);
WIRE 16 -1 (-12750 5025)(-12750 5050);
WIRE 16 -1 (-8000 4225)(-8000 4125);
WIRE 16 -1 (-12325 5600)(-12325 5700);
WIRE 16 -1 (-12200 3550)(-12200 3600);
WIRE 16 -1 (-10000 2200)(-10000 2250);
WIRE 16 -1 (-11975 4350)(-12800 4350);
FORCEPROP 2 LAST SIG_NAME VR_PVNN_PCH_AIREF1
J 0
(-12750 4365);
DISPLAY 0.617021 (-12750 4365);
PAINT ORANGE (-12750 4365);
WIRE 16 -1 (-10175 4350)(-11975 4350);
WIRE 16 -1 (-11975 4350)(-11975 4450);
WIRE 16 -1 (-11875 4450)(-11975 4450);
WIRE 16 -1 (-11975 4650)(-11975 4450);
WIRE 16 -1 (-11875 4650)(-11975 4650);
WIRE 16 -1 (-7300 2025)(-7300 1475);
WIRE 16 -1 (-5950 2025)(-7300 2025);
WIRE 16 -1 (-7300 1475)(-5950 1475);
WIRE 16 -1 (-5950 1475)(-5950 2025);
WIRE 16 -1 (-7150 3600)(-7350 3600);
WIRE 16 -1 (-7350 4850)(-7350 3600);
WIRE 16 -1 (-9275 3600)(-7350 3600);
FORCEPROP 2 LAST SIG_NAME VID_PCH_CORE_PVNN_AUX_VID_0
J 0
(-9100 3615);
DISPLAY 0.617021 (-9100 3615);
PAINT ORANGE (-9100 3615);
WIRE 3 2175 (-13650 4600)(-13075 4600);
WIRE 3 2175 (-13075 4600)(-13075 4850);
WIRE 3 2175 (-13650 4600)(-13650 4850);
WIRE 3 2175 (-13650 4850)(-13075 4850);
WIRE 3 2175 (-12075 4800)(-11450 4800);
WIRE 3 2175 (-11450 4275)(-11450 4800);
WIRE 3 2175 (-12075 4275)(-12075 4800);
WIRE 3 2175 (-12075 4275)(-11450 4275);
WIRE 3 682 (-12650 4550)(-12650 4800);
WIRE 3 682 (-12150 4550)(-12650 4550);
WIRE 3 682 (-12650 4800)(-12150 4800);
WIRE 3 682 (-12150 4800)(-12150 4550);
WIRE 16 -1 (-11675 4650)(-11600 4650);
WIRE 16 -1 (-11725 4450)(-11600 4450);
WIRE 16 -1 (-11600 4650)(-11600 4450);
WIRE 16 -1 (-11600 4450)(-11600 4300);
WIRE 16 -1 (-11600 4300)(-10175 4300);
WIRE 16 -1 (-12800 4300)(-11600 4300);
FORCEPROP 2 LAST SIG_NAME ISENSE_PVNN_PCH_PH1_IMON
J 2
(-12227 4318);
DISPLAY 0.617021 (-12227 4318);
PAINT ORANGE (-12227 4318);
WIRE 16 -1 (-10750 3000)(-10175 3000);
WIRE 16 -1 (-10750 2250)(-10750 3000);
FORCEPROP 0 LAST SIG_NAME VR_PVNN_PCH_XADDR1
R 1
J 0
(-10760 2435);
DISPLAY 0.617021 (-10760 2435);
PAINT ORANGE (-10760 2435);
FORCEPROP 2 LASTPROP $XRERR UNIQUE?
J 0
(-11000 2435);
DISPLAY 0.638298 (-11000 2435);
PAINT MONO (-11000 2435);
DISPLAY INVISIBLE (-11000 2435);
WIRE 3 2175 (-11350 2550)(-11350 3175);
WIRE 3 2175 (-11350 3175)(-10800 3175);
WIRE 3 2175 (-11350 2550)(-10800 2550);
WIRE 3 2175 (-10800 2550)(-10800 3175);
WIRE 16 -1 (-12475 1950)(-13375 1950);
FORCEPROP 2 LAST SIG_NAME VSENSE_P1V05_PCH_STBY_AVSN
J 0
(-13390 1965);
DISPLAY 0.617021 (-13390 1965);
PAINT ORANGE (-13390 1965);
WIRE 16 -1 (-12475 1975)(-12475 1950);
WIRE 16 -1 (-11800 3450)(-10175 3450);
WIRE 16 -1 (-11800 1950)(-12475 1950);
WIRE 16 -1 (-11800 1950)(-11800 3450);
WIRE 16 -1 (-10175 3350)(-12525 3350);
FORCEPROP 2 LAST SIG_NAME SMB_VR_STBY_LVC3_SDA
J 0
(-12450 3365);
DISPLAY 0.617021 (-12450 3365);
PAINT ORANGE (-12450 3365);
WIRE 16 -1 (-10175 3300)(-12525 3300);
FORCEPROP 2 LAST SIG_NAME SMB_VR_STBY_LVC3_SCL
J 0
(-12450 3315);
DISPLAY 0.617021 (-12450 3315);
PAINT ORANGE (-12450 3315);
WIRE 3 682 (-11350 3400)(-11350 3250);
WIRE 3 682 (-11000 3400)(-11350 3400);
WIRE 3 682 (-11350 3250)(-11000 3250);
WIRE 3 682 (-11000 3250)(-11000 3400);
WIRE 16 -1 (-11175 2900)(-11300 2900);
WIRE 16 -1 (-11300 2900)(-11300 3000);
WIRE 16 -1 (-11300 3000)(-11200 3000);
WIRE 16 -1 (-11300 3100)(-11300 3000);
WIRE 16 -1 (-10175 3100)(-11300 3100);
WIRE 16 -1 (-13100 3100)(-11300 3100);
FORCEPROP 2 LAST SIG_NAME VR_P1V05_PCH_BIREF1
J 2
(-12370 3100);
DISPLAY 0.617021 (-12370 3100);
PAINT ORANGE (-12370 3100);
WIRE 16 -1 (-11025 2900)(-10850 2900);
WIRE 16 -1 (-10850 2900)(-10850 3000);
WIRE 16 -1 (-11000 3000)(-10850 3000);
WIRE 16 -1 (-10850 3000)(-10850 3050);
WIRE 16 -1 (-10850 3050)(-10175 3050);
WIRE 16 -1 (-13100 3050)(-10850 3050);
FORCEPROP 2 LAST SIG_NAME ISENSE_P1V05_PCH_STBY_PH1_IMON
J 2
(-12255 3049);
DISPLAY 0.617021 (-12255 3049);
PAINT ORANGE (-12255 3049);
WIRE 3 682 (-11700 2750)(-11700 2350);
WIRE 3 682 (-11700 2750)(-11750 2750);
WIRE 3 682 (-11400 2750)(-11700 2750);
WIRE 3 682 (-11400 3000)(-11400 2750);
WIRE 3 682 (-11750 2750)(-11750 3000);
WIRE 3 682 (-11750 3000)(-11400 3000);
WIRE 16 -1 (-10000 2450)(-10000 2550);
WIRE 16 -1 (-10000 2550)(-10300 2550);
WIRE 16 -1 (-10300 2550)(-10300 3200);
WIRE 16 -1 (-10300 3200)(-10175 3200);
WIRE 16 -1 (-13100 3200)(-10300 3200);
FORCEPROP 2 LAST SIG_NAME A_TSENSE_P1V05_PCH_STBY_TMON
J 2
(-12249 3216);
DISPLAY 0.617021 (-12249 3216);
PAINT ORANGE (-12249 3216);
WIRE 16 -1 (-11850 3500)(-10175 3500);
WIRE 16 -1 (-11850 2225)(-11850 3500);
WIRE 16 -1 (-12575 2225)(-12475 2225);
WIRE 16 -1 (-12475 2175)(-12475 2225);
WIRE 16 -1 (-12475 2225)(-11850 2225);
FORCEPROP 2 LAST SIG_NAME VR_P1V05_PCH_STBY_AVSP
J 0
(-12390 2240);
DISPLAY 0.617021 (-12390 2240);
PAINT ORANGE (-12390 2240);
FORCEPROP 2 LASTPROP $XRERR UNIQUE?
J 0
(-12630 2240);
DISPLAY 0.638298 (-12630 2240);
PAINT MONO (-12630 2240);
DISPLAY INVISIBLE (-12630 2240);
WIRE 16 -1 (-10175 3550)(-11925 3550);
WIRE 16 -1 (-11925 2475)(-11925 3550);
WIRE 16 -1 (-12375 2500)(-12375 2475);
WIRE 16 -1 (-12375 2475)(-11925 2475);
WIRE 16 -1 (-13400 2475)(-12375 2475);
FORCEPROP 2 LAST SIG_NAME VSENSE_PVNN_PCH_STBY_AVSN
J 0
(-13415 2490);
DISPLAY 0.617021 (-13415 2490);
PAINT ORANGE (-13415 2490);
WIRE 16 -1 (-10450 2950)(-10175 2950);
WIRE 16 -1 (-10450 2250)(-10450 2950);
FORCEPROP 0 LAST SIG_NAME VR_PVNN_PCH_XADDR2
R 1
J 0
(-10460 2435);
DISPLAY 0.617021 (-10460 2435);
PAINT ORANGE (-10460 2435);
FORCEPROP 2 LASTPROP $XRERR UNIQUE?
J 0
(-10700 2435);
DISPLAY 0.638298 (-10700 2435);
PAINT MONO (-10700 2435);
DISPLAY INVISIBLE (-10700 2435);
WIRE 3 682 (-12850 5400)(-12850 4900);
WIRE 3 682 (-12400 5400)(-12850 5400);
WIRE 3 682 (-12850 4900)(-12400 4900);
WIRE 3 682 (-12400 4900)(-12400 5400);
WIRE 16 -1 (-11100 4700)(-11100 4800);
WIRE 16 -1 (-11100 4800)(-10800 4800);
WIRE 16 -1 (-10800 4800)(-10800 4450);
WIRE 16 -1 (-10175 4450)(-10800 4450);
FORCEPROP 2 LAST SIG_NAME PU_PVNN_PCH_VCLK
J 0
(-10750 4465);
DISPLAY 0.617021 (-10750 4465);
PAINT ORANGE (-10750 4465);
FORCEPROP 2 LASTPROP $XRERR UNIQUE?
J 0
(-10990 4465);
DISPLAY 0.638298 (-10990 4465);
PAINT MONO (-10990 4465);
DISPLAY INVISIBLE (-10990 4465);
WIRE 3 682 (-10825 4400)(-11150 4400);
WIRE 3 682 (-10825 4775)(-10825 4400);
WIRE 3 682 (-11150 4400)(-11150 4775);
WIRE 3 682 (-11150 4775)(-10825 4775);
WIRE 16 -1 (-11700 4150)(-11175 4150);
WIRE 16 -1 (-11175 4150)(-11175 4975);
WIRE 16 -1 (-11175 4150)(-10175 4150);
FORCEPROP 2 LAST SIG_NAME VR_PVNN_PCH_VREN
J 0
(-10900 4165);
DISPLAY 0.617021 (-10900 4165);
PAINT ORANGE (-10900 4165);
FORCEPROP 2 LASTPROP $XRERR UNIQUE?
J 0
(-11140 4165);
DISPLAY 0.638298 (-11140 4165);
PAINT MONO (-11140 4165);
DISPLAY INVISIBLE (-11140 4165);
WIRE 16 -1 (-11800 3900)(-12800 3900);
FORCEPROP 2 LAST SIG_NAME VR_PVNN_P1V05_PCH_VD12
J 0
(-12750 3915);
DISPLAY 0.617021 (-12750 3915);
PAINT ORANGE (-12750 3915);
WIRE 16 -1 (-11800 3900)(-11800 3850);
WIRE 16 -1 (-11100 3900)(-11800 3900);
WIRE 16 -1 (-10175 3900)(-11100 3900);
WIRE 16 -1 (-11100 4500)(-11100 3900);
WIRE 16 -1 (-12200 4200)(-12200 3800);
WIRE 16 -1 (-12200 4200)(-10175 4200);
WIRE 16 -1 (-12800 4200)(-12200 4200);
FORCEPROP 2 LAST SIG_NAME A_TSENSE_PVNN_PCH_TMON
J 2
(-12248 4220);
DISPLAY 0.617021 (-12248 4220);
PAINT ORANGE (-12248 4220);
WIRE 16 -1 (-10175 4050)(-12800 4050);
FORCEPROP 2 LAST SIG_NAME VR_PVNN_PCH_VINSEN
J 0
(-12750 4065);
DISPLAY 0.617021 (-12750 4065);
PAINT ORANGE (-12750 4065);
WIRE 16 -1 (-7000 2000)(-7000 1500);
WIRE 16 -1 (-12775 2750)(-13400 2750);
FORCEPROP 2 LAST SIG_NAME VSENSE_PVNN_PCH_STBY_AVSP
J 0
(-13365 2765);
DISPLAY 0.617021 (-13365 2765);
PAINT ORANGE (-13365 2765);
WIRE 16 -1 (-12775 2225)(-13400 2225);
FORCEPROP 2 LAST SIG_NAME VSENSE_P1V05_PCH_STBY_AVSP
J 0
(-13415 2240);
DISPLAY 0.617021 (-13415 2240);
PAINT ORANGE (-13415 2240);
WIRE 3 682 (-9200 3750)(-9150 3750);
WIRE 3 682 (-9150 3750)(-9150 3700);
WIRE 3 682 (-9150 3700)(-9200 3700);
WIRE 3 682 (-9150 3300)(-9200 3300);
WIRE 3 682 (-9150 3450)(-9150 3300);
WIRE 3 682 (-9100 3450)(-9150 3450);
WIRE 3 682 (-9200 3500)(-9150 3500);
WIRE 3 682 (-9150 3500)(-9150 3450);
WIRE 16 -1 (-11300 3650)(-11800 3650);
WIRE 16 -1 (-11300 3850)(-11300 3650);
WIRE 16 -1 (-11300 3850)(-10175 3850);
FORCEPROP 2 LAST SIG_NAME PU_PVNN_PCH_VDIO
J 0
(-10900 3865);
DISPLAY 0.617021 (-10900 3865);
PAINT ORANGE (-10900 3865);
FORCEPROP 2 LASTPROP $XRERR UNIQUE?
J 0
(-11140 3865);
DISPLAY 0.638298 (-11140 3865);
PAINT MONO (-11140 3865);
DISPLAY INVISIBLE (-11140 3865);
WIRE 16 -1 (-10175 3600)(-11975 3600);
WIRE 16 -1 (-11975 2750)(-11975 3600);
WIRE 16 -1 (-12375 2700)(-12375 2750);
WIRE 16 -1 (-12375 2750)(-11975 2750);
WIRE 16 -1 (-12575 2750)(-12375 2750);
FORCEPROP 2 LAST SIG_NAME VR_PVNN_PCH_AVSP
J 0
(-12515 2765);
DISPLAY 0.617021 (-12515 2765);
PAINT ORANGE (-12515 2765);
FORCEPROP 2 LASTPROP $XRERR UNIQUE?
J 0
(-12755 2765);
DISPLAY 0.638298 (-12755 2765);
PAINT MONO (-12755 2765);
DISPLAY INVISIBLE (-12755 2765);
WIRE 16 -1 (-7175 3950)(-9275 3950);
FORCEPROP 2 LAST SIG_NAME VR_P1V05_PCH_STBY_PWM1
J 0
(-8325 3974);
DISPLAY 0.617021 (-8325 3974);
PAINT ORANGE (-8325 3974);
WIRE 16 -1 (-7175 3650)(-7750 3650);
WIRE 16 -1 (-7750 4850)(-7750 3650);
WIRE 16 -1 (-9275 3650)(-7750 3650);
FORCEPROP 2 LAST SIG_NAME VID_PCH_CORE_PVNN_AUX_VID_1
J 0
(-9100 3665);
DISPLAY 0.617021 (-9100 3665);
PAINT ORANGE (-9100 3665);
WIRE 16 -1 (-8750 4850)(-8750 4650);
WIRE 16 -1 (-8600 4350)(-9275 4350);
FORCEPROP 2 LAST SIG_NAME PU_PVNN_PCH_PINALRT_N
J 0
(-9175 4365);
DISPLAY 0.617021 (-9175 4365);
PAINT ORANGE (-9175 4365);
FORCEPROP 2 LASTPROP $XRERR UNIQUE?
J 0
(-9415 4365);
DISPLAY 0.638298 (-9415 4365);
PAINT MONO (-9415 4365);
DISPLAY INVISIBLE (-9415 4365);
WIRE 16 -1 (-8750 4650)(-8600 4650);
WIRE 16 -1 (-8600 4650)(-8600 4350);
WIRE 16 -1 (-12800 4150)(-11900 4150);
FORCEPROP 2 LAST SIG_NAME PWRGD_P1V8_PCH_STBY
J 0
(-12750 4165);
DISPLAY 0.617021 (-12750 4165);
PAINT ORANGE (-12750 4165);
WIRE 3 682 (-12550 3850)(-12100 3850);
WIRE 3 682 (-12100 3850)(-12100 3475);
WIRE 3 682 (-12550 3475)(-12550 3850);
WIRE 3 682 (-12550 3475)(-12100 3475);
WIRE 16 -1 (-8075 4150)(-9275 4150);
FORCEPROP 2 LAST SIG_NAME IRQ_PVNN_PCH_VRHOT_N
J 0
(-9175 4165);
DISPLAY 0.617021 (-9175 4165);
PAINT ORANGE (-9175 4165);
FORCEPROP 2 LASTPROP $XRERR UNIQUE?
J 0
(-9415 4165);
DISPLAY 0.638298 (-9415 4165);
PAINT MONO (-9415 4165);
DISPLAY INVISIBLE (-9415 4165);
WIRE 16 -1 (-8075 4150)(-8075 4850);
WIRE 16 -1 (-9200 2075)(-9200 2150);
WIRE 16 -1 (-8800 2150)(-9200 2150);
WIRE 16 -1 (-8800 2075)(-8800 2150);
WIRE 16 -1 (-8800 2150)(-8150 2150);
FORCEPROP 2 LAST SIG_NAME VR_PVNN_P1V05_PCH_VD12
J 2
(-8226 2153);
DISPLAY 0.617021 (-8226 2153);
PAINT ORANGE (-8226 2153);
WIRE 16 -1 (-8400 4850)(-8400 3800);
WIRE 16 -1 (-9275 3800)(-8400 3800);
FORCEPROP 2 LAST SIG_NAME PU_VR_PVNN_PCH_FAULT1
J 0
(-9175 3815);
DISPLAY 0.617021 (-9175 3815);
PAINT ORANGE (-9175 3815);
FORCEPROP 2 LASTPROP $XRERR UNIQUE?
J 0
(-9415 3815);
DISPLAY 0.638298 (-9415 3815);
PAINT MONO (-9415 3815);
DISPLAY INVISIBLE (-9415 3815);
WIRE 16 -1 (-9275 4500)(-9100 4500);
WIRE 16 -1 (-9100 4850)(-9100 4500);
WIRE 16 -1 (-8000 4500)(-9100 4500);
FORCEPROP 2 LAST SIG_NAME PWRGD_PVNN_PCH_R
J 0
(-8990 4515);
DISPLAY 0.617021 (-8990 4515);
PAINT ORANGE (-8990 4515);
FORCEPROP 2 LASTPROP $XRERR UNIQUE?
J 0
(-9230 4515);
DISPLAY 0.638298 (-9230 4515);
PAINT MONO (-9230 4515);
DISPLAY INVISIBLE (-9230 4515);
WIRE 16 -1 (-8000 4425)(-8000 4500);
WIRE 16 -1 (-7200 4500)(-8000 4500);
WIRE 3 682 (-8850 4750)(-8500 4750);
WIRE 3 682 (-8850 5150)(-8850 4750);
WIRE 3 682 (-8500 4750)(-8500 5150);
WIRE 3 682 (-8500 5150)(-8850 5150);
WIRE 3 682 (-11850 3950)(-11850 3625);
WIRE 3 682 (-11350 3950)(-11850 3950);
WIRE 3 682 (-11850 3625)(-11350 3625);
WIRE 3 682 (-11350 3625)(-11350 3950);
WIRE 16 -1 (-7175 3900)(-9275 3900);
FORCEPROP 2 LAST SIG_NAME VR_PVNN_PCH_PWM1
J 0
(-8325 3915);
DISPLAY 0.617021 (-8325 3915);
PAINT ORANGE (-8325 3915);
WIRE 3 682 (-7800 5250)(-7800 4700);
WIRE 3 682 (-7050 5250)(-7800 5250);
WIRE 3 682 (-7800 4700)(-7050 4700);
WIRE 3 682 (-7050 4700)(-7050 5250);
WIRE 16 -1 (-7275 1525)(-6025 1525);
WIRE 16 -1 (-7275 1625)(-6025 1625);
WIRE 16 -1 (-7275 1725)(-6025 1725);
WIRE 16 -1 (-7275 1825)(-6025 1825);
WIRE 16 -1 (-6600 2000)(-6600 1500);
WIRE 16 -1 (-7275 1925)(-6025 1925);
WIRE 3 682 (-7350 1900)(-6550 1900);
WIRE 3 682 (-7350 2050)(-7350 1900);
WIRE 3 682 (-6550 1900)(-6550 2050);
WIRE 3 682 (-6550 2050)(-7350 2050);
WIRE 16 -1 (-7000 4500)(-6325 4500);
FORCEPROP 2 LAST SIG_NAME PWRGD_PVNN_P1V05_PCH
J 0
(-6900 4515);
DISPLAY 0.617021 (-6900 4515);
PAINT ORANGE (-6900 4515);
WIRE 16 682 (-7875 5925)(-7875 5350);
WIRE 16 682 (-6975 5925)(-7875 5925);
WIRE 16 682 (-7875 5350)(-6975 5350);
WIRE 16 682 (-6975 5350)(-6975 5925);
WIRE 16 682 (-6850 5925)(-6850 5350);
WIRE 16 682 (-5950 5925)(-6850 5925);
WIRE 16 682 (-6850 5350)(-5950 5350);
WIRE 16 682 (-5950 5350)(-5950 5925);
WIRE 16 -1 (-10450 4500)(-10175 4500);
WIRE 16 -1 (-10450 5225)(-10450 4500);
FORCEPROP 2 LAST SIG_NAME VR_PVNN_PCH_VDD
R 1
J 0
(-10475 4665);
DISPLAY 0.617021 (-10475 4665);
PAINT ORANGE (-10475 4665);
FORCEPROP 2 LASTPROP $XRERR UNIQUE?
J 0
(-10715 4665);
DISPLAY 0.638298 (-10715 4665);
PAINT MONO (-10715 4665);
DISPLAY INVISIBLE (-10715 4665);
WIRE 16 -1 (-10450 5325)(-10450 5225);
WIRE 16 -1 (-10150 5225)(-10450 5225);
WIRE 16 -1 (-10150 5175)(-10150 5225);
WIRE 16 -1 (-9750 5225)(-10150 5225);
WIRE 16 -1 (-9750 5175)(-9750 5225);
WIRE 16 -1 (-12325 5275)(-12325 5350);
WIRE 16 -1 (-12325 5350)(-12325 5400);
WIRE 16 -1 (-12750 5250)(-12750 5350);
WIRE 16 -1 (-12325 5350)(-12750 5350);
WIRE 16 -1 (-12750 5500)(-13100 5500);
FORCEPROP 2 LAST SIG_NAME VR_PVNN_PCH_VINSEN
J 0
(-13115 5515);
DISPLAY 0.617021 (-13115 5515);
PAINT ORANGE (-13115 5515);
WIRE 16 -1 (-12750 5500)(-12750 5350);
WIRE 3 682 (-10050 2100)(-9600 2100);
WIRE 3 682 (-9600 2500)(-9600 2100);
WIRE 3 682 (-10050 2100)(-10050 2500);
WIRE 3 682 (-10050 2500)(-9600 2500);
WIRE 3 682 (-10800 1800)(-10800 2350);
WIRE 3 682 (-10150 1800)(-10800 1800);
WIRE 3 682 (-10800 2350)(-10150 2350);
WIRE 3 682 (-10150 2350)(-10150 1800);
DOT 1 (-10850 3000);
DOT 1 (-11300 3100);
DOT 1 (-11300 3000);
DOT 1 (-10850 3050);
DOT 1 (-11600 4450);
DOT 1 (-7350 3600);
DOT 1 (-10750 1950);
DOT 1 (-7750 3650);
DOT 1 (-10150 5225);
DOT 1 (-9100 4500);
DOT 1 (-8400 5200);
DOT 1 (-8750 5200);
DOT 1 (-11600 4300);
DOT 1 (-12475 2225);
DOT 1 (-12375 2475);
DOT 1 (-12375 2750);
DOT 1 (-8800 2150);
DOT 1 (-8900 3050);
DOT 1 (-8900 3000);
DOT 1 (-11975 4350);
DOT 1 (-10450 5225);
DOT 1 (-10450 5600);
DOT 1 (-8000 4500);
DOT 1 (-12475 1950);
DOT 1 (-11975 4450);
DOT 1 (-11700 2750);
DOT 1 (-12200 4200);
DOT 1 (-10300 3200);
DOT 1 (-11800 3900);
DOT 1 (-11100 3900);
DOT 1 (-11175 4150);
DOT 1 (-9150 3450);
DOT 1 (-8075 5200);
DOT 1 (-7750 5200);
DOT 1 (-12750 5350);
DOT 1 (-12325 5350);
FORCENOTE
TP FAB1 DELETE RES 0203
(-13175 4475) 0;
DISPLAY LEFT (-13175 4475);
DISPLAY 1.021277 (-13175 4475);
PAINT RED (-13175 4475);
FORCENOTE
INFINEON:NOPOP
(-13625 4675) 0;
DISPLAY LEFT (-13625 4675);
DISPLAY 0.872340 (-13625 4675);
PAINT RED (-13625 4675);
FORCENOTE
CF23&CF24
(-13625 4725) 0;
DISPLAY LEFT (-13625 4725);
DISPLAY 0.872340 (-13625 4725);
PAINT RED (-13625 4725);
FORCENOTE
RF23&RF24
(-13625 4775) 0;
DISPLAY LEFT (-13625 4775);
DISPLAY 0.872340 (-13625 4775);
PAINT RED (-13625 4775);
FORCENOTE
FAIRCHILD:POP
(-13625 4625) 0;
DISPLAY LEFT (-13625 4625);
DISPLAY 0.872340 (-13625 4625);
PAINT RED (-13625 4625);
FORCENOTE
TP FAB1 CO-LAY WITH
(-11612 2431) 0;
DISPLAY LEFT (-11612 2431);
DISPLAY 1.021277 (-11612 2431);
PAINT RED (-11612 2431);
FORCENOTE
TP FAB1 DELETE RES 0203
(-11775 2300) 0;
DISPLAY LEFT (-11775 2300);
DISPLAY 1.021277 (-11775 2300);
PAINT RED (-11775 2300);
FORCENOTE
ROOM=PVNN_PCH_STBY
(-13550 1250) 0;
DISPLAY LEFT (-13550 1250);
DISPLAY 1.595745 (-13550 1250);
PAINT PURPLE (-13550 1250);
FORCENOTE
TP FAB1 DEL RES 0314
(-10950 3400) 0;
DISPLAY LEFT (-10950 3400);
DISPLAY 1.021277 (-10950 3400);
PAINT RED (-10950 3400);
FORCENOTE
TP FAB1 CO-LAY WITH FAIRCHILD PARTS 1203
(-12087 4831) 0;
DISPLAY LEFT (-12087 4831);
DISPLAY 1.021277 (-12087 4831);
PAINT RED (-12087 4831);
FORCENOTE
FAIRCHILD PARTS 1203
(-11612 2381) 0;
DISPLAY LEFT (-11612 2381);
DISPLAY 1.021277 (-11612 2381);
PAINT RED (-11612 2381);
FORCENOTE
SW FREQ: 833KHZ
(-7814 5399) 0;
DISPLAY LEFT (-7814 5399);
DISPLAY 0.808511 (-7814 5399);
PAINT PURPLE (-7814 5399);
FORCENOTE
SW FREQ: 833KHZ
(-6779 5402) 0;
DISPLAY LEFT (-6779 5402);
DISPLAY 0.808511 (-6779 5402);
PAINT PURPLE (-6779 5402);
FORCENOTE
PVNN_PCH SPEC:
(-6825 5850) 0;
DISPLAY LEFT (-6825 5850);
DISPLAY 0.808511 (-6825 5850);
PAINT PURPLE (-6825 5850);
FORCENOTE
VOUT=0.85V TO 1.0V
(-6800 5775) 0;
DISPLAY LEFT (-6800 5775);
DISPLAY 0.808511 (-6800 5775);
PAINT PURPLE (-6800 5775);
FORCENOTE
TDC=18A
(-6800 5725) 0;
DISPLAY LEFT (-6800 5725);
DISPLAY 0.808511 (-6800 5725);
PAINT PURPLE (-6800 5725);
FORCENOTE
STEP=TBD
(-6775 5625) 0;
DISPLAY LEFT (-6775 5625);
DISPLAY 0.808511 (-6775 5625);
PAINT PURPLE (-6775 5625);
FORCENOTE
DC TOL= +/-1.5%
(-6775 5525) 0;
DISPLAY LEFT (-6775 5525);
DISPLAY 0.808511 (-6775 5525);
PAINT PURPLE (-6775 5525);
FORCENOTE
AC TOL + RIPPLE=+/-3.0%
(-6775 5475) 0;
DISPLAY LEFT (-6775 5475);
DISPLAY 0.808511 (-6775 5475);
PAINT PURPLE (-6775 5475);
FORCENOTE
TP FAB1 POP RES 0523
(-7000 4700) 0;
DISPLAY LEFT (-7000 4700);
DISPLAY 1.021277 (-7000 4700);
PAINT RED (-7000 4700);
FORCENOTE
STEP RATE=TBDA/US
(-6775 5575) 0;
DISPLAY LEFT (-6775 5575);
DISPLAY 0.808511 (-6775 5575);
PAINT PURPLE (-6775 5575);
FORCENOTE
PK=20.5A
(-6775 5675) 0;
DISPLAY LEFT (-6775 5675);
DISPLAY 0.808511 (-6775 5675);
PAINT PURPLE (-6775 5675);
FORCENOTE
TP FAB1 SWAP AVID1 AND AVID0 0203
(-7325 2450) 0;
DISPLAY LEFT (-7325 2450);
DISPLAY 1.021277 (-7325 2450);
PAINT RED (-7325 2450);
FORCENOTE
AC TOL + RIPPLE=+/-3.0%
(-7800 5475) 0;
DISPLAY LEFT (-7800 5475);
DISPLAY 0.808511 (-7800 5475);
PAINT PURPLE (-7800 5475);
FORCENOTE
TP FAB1 NC 0321
(-10975 3725) 0;
DISPLAY LEFT (-10975 3725);
DISPLAY 1.021277 (-10975 3725);
PAINT RED (-10975 3725);
FORCENOTE
TDC=12A
(-7825 5725) 0;
DISPLAY LEFT (-7825 5725);
DISPLAY 0.808511 (-7825 5725);
PAINT PURPLE (-7825 5725);
FORCENOTE
TP FAB1 ADD RES 0317
(-8850 5225) 0;
DISPLAY LEFT (-8850 5225);
DISPLAY 1.021277 (-8850 5225);
PAINT RED (-8850 5225);
FORCENOTE
TP FAB1 NC 0321
(-9100 3725) 0;
DISPLAY LEFT (-9100 3725);
DISPLAY 1.021277 (-9100 3725);
PAINT RED (-9100 3725);
FORCENOTE
TP FAB1 DEL NETS 0309
(-9050 3450) 0;
DISPLAY LEFT (-9050 3450);
DISPLAY 1.021277 (-9050 3450);
PAINT RED (-9050 3450);
FORCENOTE
TP FAB1 ADD CAP 0218
(-10150 2050) 0;
DISPLAY LEFT (-10150 2050);
DISPLAY 1.021277 (-10150 2050);
PAINT RED (-10150 2050);
FORCENOTE
TP FAB1 CHANGE RES R2L9 AND NOPOP R8A2 0408
(-10800 1750) 0;
DISPLAY LEFT (-10800 1750);
DISPLAY 0.638298 (-10800 1750);
PAINT RED (-10800 1750);
FORCENOTE
TP FAB3 CHANGE R2L9 AND POP R8A2
(-10800 1650) 0;
DISPLAY LEFT (-10800 1650);
DISPLAY 0.638298 (-10800 1650);
PAINT RED (-10800 1650);
FORCENOTE
TP FAB1 CHANGE R2L9 RES 0523
(-10800 1700) 0;
DISPLAY LEFT (-10800 1700);
DISPLAY 0.638298 (-10800 1700);
PAINT RED (-10800 1700);
FORCENOTE
DC TOL= +/-1.5%
(-7800 5525) 0;
DISPLAY LEFT (-7800 5525);
DISPLAY 0.808511 (-7800 5525);
PAINT PURPLE (-7800 5525);
FORCENOTE
PK=15A
(-7800 5675) 0;
DISPLAY LEFT (-7800 5675);
DISPLAY 0.808511 (-7800 5675);
PAINT PURPLE (-7800 5675);
FORCENOTE
P1V05_PCH SPEC:
(-7825 5850) 0;
DISPLAY LEFT (-7825 5850);
DISPLAY 0.808511 (-7825 5850);
PAINT PURPLE (-7825 5850);
FORCENOTE
TP FAB1 ADD RES 0218
(-11275 3625) 0;
DISPLAY LEFT (-11275 3625);
DISPLAY 1.021277 (-11275 3625);
PAINT RED (-11275 3625);
FORCENOTE
TP FAB1 ADD RES 0218
(-10800 4375) 0;
DISPLAY LEFT (-10800 4375);
DISPLAY 1.021277 (-10800 4375);
PAINT RED (-10800 4375);
FORCENOTE
TP FAB1 NC 0321
(-9200 4025) 0;
DISPLAY LEFT (-9200 4025);
DISPLAY 1.021277 (-9200 4025);
PAINT RED (-9200 4025);
FORCENOTE
VERIFY
(-7250 2300) 0;
DISPLAY LEFT (-7250 2300);
DISPLAY 1.021277 (-7250 2300);
PAINT PURPLE (-7250 2300);
FORCENOTE
TP FAB1 ADD CAP 0218
(-12950 3425) 0;
DISPLAY LEFT (-12950 3425);
DISPLAY 1.021277 (-12950 3425);
PAINT RED (-12950 3425);
FORCENOTE
VOUT=1.05V
(-7825 5775) 0;
DISPLAY LEFT (-7825 5775);
DISPLAY 0.808511 (-7825 5775);
PAINT PURPLE (-7825 5775);
FORCENOTE
STEP=TBD
(-7800 5625) 0;
DISPLAY LEFT (-7800 5625);
DISPLAY 0.808511 (-7800 5625);
PAINT PURPLE (-7800 5625);
FORCENOTE
STEP RATE=TBDA/US
(-7800 5575) 0;
DISPLAY LEFT (-7800 5575);
DISPLAY 0.808511 (-7800 5575);
PAINT PURPLE (-7800 5575);
FORCENOTE
TP FAB3 CHANGE CAP 0912
(-12900 4850) 0;
DISPLAY LEFT (-12900 4850);
DISPLAY 0.638298 (-12900 4850);
PAINT RED (-12900 4850);
FORCENOTE
TP FAB1 NC 0321
(-10975 3975) 0;
DISPLAY LEFT (-10975 3975);
DISPLAY 1.021277 (-10975 3975);
PAINT RED (-10975 3975);
QUIT
